G04 ================== begin FILE IDENTIFICATION RECORD ==================*
G04 Layout Name:  D:/<user>/Wistron_project/16316-1/gbr-0621/16316-1.brd*
G04 Film Name:    DP_REF_L1*
G04 File Format:  Gerber RS274X*
G04 File Origin:  Cadence Allegro 16.5-S056*
G04 Origin Date:  Wed Jun 21 09:32:22 2017*
G04 *
G04 Layer:  BOARD GEOMETRY/DP_REF_L1_TBL*
G04 Layer:  BOARD GEOMETRY/DP_REF_L1_TOP*
G04 Layer:  BOARD GEOMETRY/PANEL_OUTLINE*
G04 *
G04 Offset:    (0.00 0.00)*
G04 Mirror:    No*
G04 Mode:      Positive*
G04 Rotation:  0*
G04 FullContactRelief:  No*
G04 UndefLineWidth:     6.00*
G04 ================== end FILE IDENTIFICATION RECORD ====================*
%FSLAX35Y35*MOIN*%
%IR0*IPPOS*OFA0.00000B0.00000*MIA0B0*SFA1.00000B1.00000*%
%ADD10C,.02*%
%ADD11C,.006*%
%ADD12C,.0049*%
%ADD13C,.00575*%
G75*
%LPD*%
G75*
G54D10*
G01X877071Y397916D02*
X1629571D01*
G01X877071Y363266D02*
X1629571D01*
G01X877071Y536516D02*
Y363266D01*
G01Y467216D02*
X1629571D01*
G01X877071Y432566D02*
X1629571D01*
G01X877071Y536516D02*
X1629571D01*
G01X877071Y501866D02*
X1629571D01*
G01X1052071Y536516D02*
Y363266D01*
G01X1314571Y536516D02*
Y363266D01*
G01X1419571Y536516D02*
Y363266D01*
G01X1629571Y536516D02*
Y363266D01*
G54D11*
G01X6250Y-135162D02*
Y-152662D01*
G01X1228Y-135162D02*
X11272D01*
G01X20038Y-152662D02*
Y-135162D01*
G01Y-143620D02*
X21130Y-142162D01*
X22222Y-141287D01*
X23968Y-140996D01*
X25278Y-141287D01*
X26807Y-142454D01*
X27462Y-144204D01*
Y-152662D01*
G01X41250Y-140996D02*
Y-152662D01*
G01Y-136329D02*
X40813Y-136037D01*
Y-135454D01*
X41250Y-135162D01*
X41687Y-135454D01*
Y-136037D01*
X41250Y-136329D01*
G01X55475Y-150621D02*
X56567Y-151787D01*
X58095Y-152662D01*
X59405D01*
X60715Y-152079D01*
X61588Y-151204D01*
X62025Y-150038D01*
X61807Y-148287D01*
X60933Y-147412D01*
X57003Y-145662D01*
X56130Y-143620D01*
X56567Y-142162D01*
X57440Y-141287D01*
X58750Y-140996D01*
X60060Y-141287D01*
X61370Y-142162D01*
G01X90693Y-157037D02*
X92222Y-158204D01*
X93968Y-158495D01*
X95496Y-158204D01*
X96807Y-156746D01*
X97680Y-154704D01*
Y-140996D01*
G01Y-143329D02*
X96807Y-142162D01*
X95496Y-141287D01*
X93968Y-140996D01*
X92222Y-141579D01*
X91130Y-142745D01*
X90256Y-144787D01*
X89820Y-146829D01*
X90038Y-148579D01*
X90912Y-150621D01*
X92222Y-152079D01*
X93968Y-152662D01*
X95278Y-152370D01*
X96807Y-151204D01*
X97680Y-150038D01*
G01X107975Y-144787D02*
X114962D01*
X114307Y-142745D01*
X113215Y-141579D01*
X111687Y-140996D01*
X110158Y-141287D01*
X108848Y-142162D01*
X107975Y-144204D01*
X107538Y-145954D01*
Y-147704D01*
X107975Y-149454D01*
X109067Y-151204D01*
X110377Y-152370D01*
X111905Y-152662D01*
X113433Y-152079D01*
X114962Y-150329D01*
G01X125693Y-152662D02*
Y-140996D01*
G01Y-143329D02*
X126785Y-142162D01*
X127877Y-141287D01*
X129405Y-140996D01*
X130496Y-141287D01*
X131807Y-142162D01*
G01X142320Y-152662D02*
Y-135162D01*
G01Y-143912D02*
X143412Y-142162D01*
X144722Y-141287D01*
X146032Y-140996D01*
X147996Y-141579D01*
X149307Y-142745D01*
X150180Y-144787D01*
Y-147120D01*
X149743Y-149454D01*
X148870Y-151204D01*
X147342Y-152370D01*
X146032Y-152662D01*
X144722Y-152370D01*
X143412Y-151496D01*
X142320Y-150038D01*
G01X160475Y-144787D02*
X167462D01*
X166807Y-142745D01*
X165715Y-141579D01*
X164187Y-140996D01*
X162658Y-141287D01*
X161348Y-142162D01*
X160475Y-144204D01*
X160038Y-145954D01*
Y-147704D01*
X160475Y-149454D01*
X161567Y-151204D01*
X162877Y-152370D01*
X164405Y-152662D01*
X165933Y-152079D01*
X167462Y-150329D01*
G01X178193Y-152662D02*
Y-140996D01*
G01Y-143329D02*
X179285Y-142162D01*
X180377Y-141287D01*
X181905Y-140996D01*
X182996Y-141287D01*
X184307Y-142162D01*
G01X216250Y-140996D02*
Y-152662D01*
G01Y-136329D02*
X215813Y-136037D01*
Y-135454D01*
X216250Y-135162D01*
X216687Y-135454D01*
Y-136037D01*
X216250Y-136329D01*
G01X230475Y-150621D02*
X231567Y-151787D01*
X233095Y-152662D01*
X234405D01*
X235715Y-152079D01*
X236588Y-151204D01*
X237025Y-150038D01*
X236807Y-148287D01*
X235933Y-147412D01*
X232003Y-145662D01*
X231130Y-143620D01*
X231567Y-142162D01*
X232440Y-141287D01*
X233750Y-140996D01*
X235060Y-141287D01*
X236370Y-142162D01*
G01X265256Y-157037D02*
X266785Y-158204D01*
X268095Y-158495D01*
X269842Y-157912D01*
X271152Y-156454D01*
X271807Y-153828D01*
Y-140996D01*
G01Y-136329D02*
X271370Y-136037D01*
Y-135454D01*
X271807Y-135162D01*
X272243Y-135454D01*
Y-136037D01*
X271807Y-136329D01*
G01X282538Y-140996D02*
Y-149162D01*
X283412Y-151204D01*
X284722Y-152370D01*
X286250Y-152662D01*
X287778Y-152370D01*
X289088Y-151204D01*
X289962Y-149162D01*
G01Y-152662D02*
Y-140996D01*
G01X300475Y-150621D02*
X301567Y-151787D01*
X303095Y-152662D01*
X304405D01*
X305715Y-152079D01*
X306588Y-151204D01*
X307025Y-150038D01*
X306807Y-148287D01*
X305933Y-147412D01*
X302003Y-145662D01*
X301130Y-143620D01*
X301567Y-142162D01*
X302440Y-141287D01*
X303750Y-140996D01*
X305060Y-141287D01*
X306370Y-142162D01*
G01X321250Y-135162D02*
Y-152662D01*
G01X318193Y-140996D02*
X324307D01*
G01X354940Y-152662D02*
Y-137787D01*
X355377Y-136329D01*
X356250Y-135454D01*
X357560Y-135162D01*
X358870Y-135745D01*
X359525Y-137204D01*
G01X356905Y-142162D02*
X352538D01*
G01X373750Y-152662D02*
X372440Y-152370D01*
X371130Y-151204D01*
X370256Y-149162D01*
X369820Y-146829D01*
X370256Y-144495D01*
X371130Y-142454D01*
X372440Y-141287D01*
X373750Y-140996D01*
X375060Y-141287D01*
X376370Y-142454D01*
X377243Y-144495D01*
X377462Y-146829D01*
X377243Y-149162D01*
X376370Y-151204D01*
X375060Y-152370D01*
X373750Y-152662D01*
G01X388193D02*
Y-140996D01*
G01Y-143329D02*
X389285Y-142162D01*
X390377Y-141287D01*
X391905Y-140996D01*
X392996Y-141287D01*
X394307Y-142162D01*
G01X421665Y-157912D02*
X422975Y-158495D01*
X424722Y-157912D01*
X425813Y-156746D01*
X426687Y-155287D01*
X427996Y-150621D01*
X430835Y-140996D01*
G01X423848D02*
X427996Y-150621D01*
G01X443750Y-152662D02*
X442440Y-152370D01*
X441130Y-151204D01*
X440256Y-149162D01*
X439820Y-146829D01*
X440256Y-144495D01*
X441130Y-142454D01*
X442440Y-141287D01*
X443750Y-140996D01*
X445060Y-141287D01*
X446370Y-142454D01*
X447243Y-144495D01*
X447462Y-146829D01*
X447243Y-149162D01*
X446370Y-151204D01*
X445060Y-152370D01*
X443750Y-152662D01*
G01X457538Y-140996D02*
Y-149162D01*
X458412Y-151204D01*
X459722Y-152370D01*
X461250Y-152662D01*
X462778Y-152370D01*
X464088Y-151204D01*
X464962Y-149162D01*
G01Y-152662D02*
Y-140996D01*
G01X475693Y-152662D02*
Y-140996D01*
G01Y-143329D02*
X476785Y-142162D01*
X477877Y-141287D01*
X479405Y-140996D01*
X480496Y-141287D01*
X481807Y-142162D01*
G01X510693Y-152662D02*
Y-140996D01*
G01Y-143329D02*
X511785Y-142162D01*
X512877Y-141287D01*
X514405Y-140996D01*
X515496Y-141287D01*
X516807Y-142162D01*
G01X527975Y-144787D02*
X534962D01*
X534307Y-142745D01*
X533215Y-141579D01*
X531687Y-140996D01*
X530158Y-141287D01*
X528848Y-142162D01*
X527975Y-144204D01*
X527538Y-145954D01*
Y-147704D01*
X527975Y-149454D01*
X529067Y-151204D01*
X530377Y-152370D01*
X531905Y-152662D01*
X533433Y-152079D01*
X534962Y-150329D01*
G01X547440Y-152662D02*
Y-137787D01*
X547877Y-136329D01*
X548750Y-135454D01*
X550060Y-135162D01*
X551370Y-135745D01*
X552025Y-137204D01*
G01X549405Y-142162D02*
X545038D01*
G01X562975Y-144787D02*
X569962D01*
X569307Y-142745D01*
X568215Y-141579D01*
X566687Y-140996D01*
X565158Y-141287D01*
X563848Y-142162D01*
X562975Y-144204D01*
X562538Y-145954D01*
Y-147704D01*
X562975Y-149454D01*
X564067Y-151204D01*
X565377Y-152370D01*
X566905Y-152662D01*
X568433Y-152079D01*
X569962Y-150329D01*
G01X580693Y-152662D02*
Y-140996D01*
G01Y-143329D02*
X581785Y-142162D01*
X582877Y-141287D01*
X584405Y-140996D01*
X585496Y-141287D01*
X586807Y-142162D01*
G01X597975Y-144787D02*
X604962D01*
X604307Y-142745D01*
X603215Y-141579D01*
X601687Y-140996D01*
X600158Y-141287D01*
X598848Y-142162D01*
X597975Y-144204D01*
X597538Y-145954D01*
Y-147704D01*
X597975Y-149454D01*
X599067Y-151204D01*
X600377Y-152370D01*
X601905Y-152662D01*
X603433Y-152079D01*
X604962Y-150329D01*
G01X615038Y-152662D02*
Y-140996D01*
G01Y-143912D02*
X615912Y-142454D01*
X617222Y-141287D01*
X618968Y-140996D01*
X620496Y-141287D01*
X621807Y-142454D01*
X622462Y-144495D01*
Y-152662D01*
G01X639743Y-142454D02*
X638215Y-141287D01*
X636905Y-140996D01*
X635158Y-141579D01*
X633848Y-142745D01*
X632975Y-144787D01*
X632756Y-146829D01*
X632975Y-148871D01*
X633848Y-150621D01*
X635158Y-152079D01*
X636905Y-152662D01*
X638433Y-152079D01*
X639743Y-150912D01*
G01X650475Y-144787D02*
X657462D01*
X656807Y-142745D01*
X655715Y-141579D01*
X654187Y-140996D01*
X652658Y-141287D01*
X651348Y-142162D01*
X650475Y-144204D01*
X650038Y-145954D01*
Y-147704D01*
X650475Y-149454D01*
X651567Y-151204D01*
X652877Y-152370D01*
X654405Y-152662D01*
X655933Y-152079D01*
X657462Y-150329D01*
G01X688750Y-135162D02*
Y-152662D01*
G01X685693Y-140996D02*
X691807D01*
G01X706250Y-152662D02*
X704940Y-152370D01*
X703630Y-151204D01*
X702756Y-149162D01*
X702320Y-146829D01*
X702756Y-144495D01*
X703630Y-142454D01*
X704940Y-141287D01*
X706250Y-140996D01*
X707560Y-141287D01*
X708870Y-142454D01*
X709743Y-144495D01*
X709962Y-146829D01*
X709743Y-149162D01*
X708870Y-151204D01*
X707560Y-152370D01*
X706250Y-152662D01*
G01X739940D02*
Y-137787D01*
X740377Y-136329D01*
X741250Y-135454D01*
X742560Y-135162D01*
X743870Y-135745D01*
X744525Y-137204D01*
G01X741905Y-142162D02*
X737538D01*
G01X758750Y-140996D02*
Y-152662D01*
G01Y-136329D02*
X758313Y-136037D01*
Y-135454D01*
X758750Y-135162D01*
X759187Y-135454D01*
Y-136037D01*
X758750Y-136329D01*
G01X772538Y-152662D02*
Y-140996D01*
G01Y-143912D02*
X773412Y-142454D01*
X774722Y-141287D01*
X776468Y-140996D01*
X777996Y-141287D01*
X779307Y-142454D01*
X779962Y-144495D01*
Y-152662D01*
G01X797680Y-135162D02*
Y-152662D01*
G01Y-150038D02*
X796807Y-151496D01*
X795496Y-152370D01*
X793968Y-152662D01*
X792222Y-152079D01*
X790912Y-150621D01*
X790038Y-148871D01*
X789820Y-146829D01*
X790038Y-144787D01*
X790912Y-143037D01*
X792222Y-141579D01*
X793968Y-140996D01*
X795496Y-141287D01*
X796588Y-141871D01*
X797680Y-143037D01*
G01X828750Y-135162D02*
Y-152662D01*
G01X825693Y-140996D02*
X831807D01*
G01X842538Y-152662D02*
Y-135162D01*
G01Y-143620D02*
X843630Y-142162D01*
X844722Y-141287D01*
X846468Y-140996D01*
X847778Y-141287D01*
X849307Y-142454D01*
X849962Y-144204D01*
Y-152662D01*
G01X860475Y-144787D02*
X867462D01*
X866807Y-142745D01*
X865715Y-141579D01*
X864187Y-140996D01*
X862658Y-141287D01*
X861348Y-142162D01*
X860475Y-144204D01*
X860038Y-145954D01*
Y-147704D01*
X860475Y-149454D01*
X861567Y-151204D01*
X862877Y-152370D01*
X864405Y-152662D01*
X865933Y-152079D01*
X867462Y-150329D01*
G01X893947Y-152662D02*
Y-135162D01*
X898313D01*
X900060Y-136037D01*
X901370Y-137204D01*
X902462Y-138953D01*
X903335Y-140996D01*
X903553Y-143912D01*
X903335Y-146829D01*
X902462Y-148871D01*
X901370Y-150621D01*
X900060Y-151787D01*
X898313Y-152662D01*
X893947D01*
G01X911883D02*
Y-135162D01*
X917123D01*
X918870Y-136037D01*
X920180Y-138079D01*
X920617Y-140412D01*
X920180Y-142745D01*
X919088Y-144495D01*
X917123Y-145371D01*
X911883D01*
G01X951250Y-140996D02*
Y-152662D01*
G01Y-136329D02*
X950813Y-136037D01*
Y-135454D01*
X951250Y-135162D01*
X951687Y-135454D01*
Y-136037D01*
X951250Y-136329D01*
G01X962200Y-152662D02*
Y-140996D01*
G01Y-144204D02*
X962855Y-142745D01*
X963947Y-141579D01*
X965475Y-140996D01*
X967003Y-141579D01*
X968095Y-142745D01*
X968750Y-144204D01*
Y-152662D01*
G01Y-144204D02*
X969405Y-142745D01*
X970496Y-141579D01*
X972025Y-140996D01*
X973553Y-141579D01*
X974645Y-142745D01*
X975300Y-144495D01*
Y-152662D01*
G01X982320Y-158495D02*
Y-140996D01*
G01Y-143620D02*
X983412Y-142162D01*
X984503Y-141287D01*
X986250Y-140996D01*
X987778Y-141287D01*
X989307Y-142745D01*
X989962Y-144787D01*
X990180Y-146829D01*
X989962Y-148871D01*
X989307Y-150912D01*
X987996Y-152079D01*
X986250Y-152662D01*
X984722Y-152370D01*
X983193Y-151496D01*
X982320Y-150329D01*
G01X1000475Y-144787D02*
X1007462D01*
X1006807Y-142745D01*
X1005715Y-141579D01*
X1004187Y-140996D01*
X1002658Y-141287D01*
X1001348Y-142162D01*
X1000475Y-144204D01*
X1000038Y-145954D01*
Y-147704D01*
X1000475Y-149454D01*
X1001567Y-151204D01*
X1002877Y-152370D01*
X1004405Y-152662D01*
X1005933Y-152079D01*
X1007462Y-150329D01*
G01X1025180Y-135162D02*
Y-152662D01*
G01Y-150038D02*
X1024307Y-151496D01*
X1022996Y-152370D01*
X1021468Y-152662D01*
X1019722Y-152079D01*
X1018412Y-150621D01*
X1017538Y-148871D01*
X1017320Y-146829D01*
X1017538Y-144787D01*
X1018412Y-143037D01*
X1019722Y-141579D01*
X1021468Y-140996D01*
X1022996Y-141287D01*
X1024088Y-141871D01*
X1025180Y-143037D01*
G01X1042680Y-152662D02*
Y-140996D01*
G01Y-143037D02*
X1041807Y-141871D01*
X1040496Y-141287D01*
X1038968Y-140996D01*
X1037440Y-141579D01*
X1036130Y-142745D01*
X1035256Y-144495D01*
X1034820Y-146829D01*
X1035256Y-149162D01*
X1036130Y-150912D01*
X1037440Y-152079D01*
X1038968Y-152662D01*
X1040496Y-152370D01*
X1041807Y-151496D01*
X1042680Y-150329D01*
G01X1052538Y-152662D02*
Y-140996D01*
G01Y-143912D02*
X1053412Y-142454D01*
X1054722Y-141287D01*
X1056468Y-140996D01*
X1057996Y-141287D01*
X1059307Y-142454D01*
X1059962Y-144495D01*
Y-152662D01*
G01X1077243Y-142454D02*
X1075715Y-141287D01*
X1074405Y-140996D01*
X1072658Y-141579D01*
X1071348Y-142745D01*
X1070475Y-144787D01*
X1070256Y-146829D01*
X1070475Y-148871D01*
X1071348Y-150621D01*
X1072658Y-152079D01*
X1074405Y-152662D01*
X1075933Y-152079D01*
X1077243Y-150912D01*
G01X1087975Y-144787D02*
X1094962D01*
X1094307Y-142745D01*
X1093215Y-141579D01*
X1091687Y-140996D01*
X1090158Y-141287D01*
X1088848Y-142162D01*
X1087975Y-144204D01*
X1087538Y-145954D01*
Y-147704D01*
X1087975Y-149454D01*
X1089067Y-151204D01*
X1090377Y-152370D01*
X1091905Y-152662D01*
X1093433Y-152079D01*
X1094962Y-150329D01*
G01X1126250Y-135162D02*
Y-152662D01*
G01X1123193Y-140996D02*
X1129307D01*
G01X1140693Y-152662D02*
Y-140996D01*
G01Y-143329D02*
X1141785Y-142162D01*
X1142877Y-141287D01*
X1144405Y-140996D01*
X1145496Y-141287D01*
X1146807Y-142162D01*
G01X1165180Y-152662D02*
Y-140996D01*
G01Y-143037D02*
X1164307Y-141871D01*
X1162996Y-141287D01*
X1161468Y-140996D01*
X1159940Y-141579D01*
X1158630Y-142745D01*
X1157756Y-144495D01*
X1157320Y-146829D01*
X1157756Y-149162D01*
X1158630Y-150912D01*
X1159940Y-152079D01*
X1161468Y-152662D01*
X1162996Y-152370D01*
X1164307Y-151496D01*
X1165180Y-150329D01*
G01X1182243Y-142454D02*
X1180715Y-141287D01*
X1179405Y-140996D01*
X1177658Y-141579D01*
X1176348Y-142745D01*
X1175475Y-144787D01*
X1175256Y-146829D01*
X1175475Y-148871D01*
X1176348Y-150621D01*
X1177658Y-152079D01*
X1179405Y-152662D01*
X1180933Y-152079D01*
X1182243Y-150912D01*
G01X1192975Y-144787D02*
X1199962D01*
X1199307Y-142745D01*
X1198215Y-141579D01*
X1196687Y-140996D01*
X1195158Y-141287D01*
X1193848Y-142162D01*
X1192975Y-144204D01*
X1192538Y-145954D01*
Y-147704D01*
X1192975Y-149454D01*
X1194067Y-151204D01*
X1195377Y-152370D01*
X1196905Y-152662D01*
X1198433Y-152079D01*
X1199962Y-150329D01*
G01X1210475Y-150621D02*
X1211567Y-151787D01*
X1213095Y-152662D01*
X1214405D01*
X1215715Y-152079D01*
X1216588Y-151204D01*
X1217025Y-150038D01*
X1216807Y-148287D01*
X1215933Y-147412D01*
X1212003Y-145662D01*
X1211130Y-143620D01*
X1211567Y-142162D01*
X1212440Y-141287D01*
X1213750Y-140996D01*
X1215060Y-141287D01*
X1216370Y-142162D01*
G01X1248750Y-140996D02*
Y-152662D01*
G01Y-136329D02*
X1248313Y-136037D01*
Y-135454D01*
X1248750Y-135162D01*
X1249187Y-135454D01*
Y-136037D01*
X1248750Y-136329D01*
G01X1262538Y-152662D02*
Y-140996D01*
G01Y-143912D02*
X1263412Y-142454D01*
X1264722Y-141287D01*
X1266468Y-140996D01*
X1267996Y-141287D01*
X1269307Y-142454D01*
X1269962Y-144495D01*
Y-152662D01*
G01X1301250D02*
Y-135162D01*
G01X1322680Y-152662D02*
Y-140996D01*
G01Y-143037D02*
X1321807Y-141871D01*
X1320496Y-141287D01*
X1318968Y-140996D01*
X1317440Y-141579D01*
X1316130Y-142745D01*
X1315256Y-144495D01*
X1314820Y-146829D01*
X1315256Y-149162D01*
X1316130Y-150912D01*
X1317440Y-152079D01*
X1318968Y-152662D01*
X1320496Y-152370D01*
X1321807Y-151496D01*
X1322680Y-150329D01*
G01X1331665Y-157912D02*
X1332975Y-158495D01*
X1334722Y-157912D01*
X1335813Y-156746D01*
X1336687Y-155287D01*
X1337996Y-150621D01*
X1340835Y-140996D01*
G01X1333848D02*
X1337996Y-150621D01*
G01X1350475Y-144787D02*
X1357462D01*
X1356807Y-142745D01*
X1355715Y-141579D01*
X1354187Y-140996D01*
X1352658Y-141287D01*
X1351348Y-142162D01*
X1350475Y-144204D01*
X1350038Y-145954D01*
Y-147704D01*
X1350475Y-149454D01*
X1351567Y-151204D01*
X1352877Y-152370D01*
X1354405Y-152662D01*
X1355933Y-152079D01*
X1357462Y-150329D01*
G01X1368193Y-152662D02*
Y-140996D01*
G01Y-143329D02*
X1369285Y-142162D01*
X1370377Y-141287D01*
X1371905Y-140996D01*
X1372996Y-141287D01*
X1374307Y-142162D01*
G01X1401883Y-135162D02*
Y-152662D01*
X1410617D01*
G01X1423750D02*
Y-135162D01*
X1421130Y-138662D01*
G01Y-152662D02*
X1426370D01*
G01X1441250Y-153245D02*
X1440813Y-152954D01*
Y-152370D01*
X1441250Y-152079D01*
X1441687Y-152370D01*
Y-152954D01*
X1441250Y-153245D01*
G01X878818Y546266D02*
Y563766D01*
X883184D01*
X884931Y562891D01*
X886241Y561724D01*
X887333Y559975D01*
X888206Y557932D01*
X888424Y555016D01*
X888206Y552099D01*
X887333Y550057D01*
X886241Y548307D01*
X884931Y547141D01*
X883184Y546266D01*
X878818D01*
G01X896754D02*
Y563766D01*
X901994D01*
X903741Y562891D01*
X905051Y560849D01*
X905488Y558516D01*
X905051Y556183D01*
X903959Y554433D01*
X901994Y553557D01*
X896754D01*
G01X933501Y563766D02*
X938741D01*
G01X936121D02*
Y546266D01*
G01X933501D02*
X938741D01*
G01X947944D02*
Y563766D01*
X953621Y549183D01*
X959298Y563766D01*
Y546266D01*
G01X966754D02*
Y563766D01*
X971994D01*
X973741Y562891D01*
X975051Y560849D01*
X975488Y558516D01*
X975051Y556183D01*
X973959Y554433D01*
X971994Y553557D01*
X966754D01*
G01X992988Y546266D02*
X984254D01*
Y563766D01*
X992988D01*
G01X989494Y555308D02*
X984254D01*
G01X1001318Y546266D02*
Y563766D01*
X1005684D01*
X1007431Y562891D01*
X1008741Y561724D01*
X1009833Y559975D01*
X1010706Y557932D01*
X1010924Y555016D01*
X1010706Y552099D01*
X1009833Y550057D01*
X1008741Y548307D01*
X1007431Y547141D01*
X1005684Y546266D01*
X1001318D01*
G01X1018162D02*
X1023621Y563766D01*
X1029080Y546266D01*
G01X1027114Y552391D02*
X1020127D01*
G01X1036099Y546266D02*
Y563766D01*
X1046143Y546266D01*
Y563766D01*
G01X1063424Y562307D02*
X1062114Y563183D01*
X1060586Y563766D01*
X1058839D01*
X1056874Y562891D01*
X1055346Y561433D01*
X1054254Y559682D01*
X1053381Y556766D01*
X1053162Y554141D01*
X1053599Y551516D01*
X1054254Y549766D01*
X1055564Y548016D01*
X1057093Y546849D01*
X1058621Y546266D01*
X1060149D01*
X1061678Y546849D01*
X1062988Y547724D01*
X1064080Y548890D01*
G01X1080488Y546266D02*
X1071754D01*
Y563766D01*
X1080488D01*
G01X1076994Y555308D02*
X1071754D01*
G01X1111121Y563766D02*
Y546266D01*
G01X1106099Y563766D02*
X1116143D01*
G01X1123162Y546266D02*
X1128621Y563766D01*
X1134080Y546266D01*
G01X1132114Y552391D02*
X1125127D01*
G01X1147867Y555599D02*
X1148741Y556474D01*
X1149396Y557932D01*
X1149833Y559975D01*
X1149396Y561724D01*
X1148523Y562891D01*
X1146994Y563766D01*
X1141099D01*
Y546266D01*
X1148304D01*
X1149833Y547432D01*
X1150706Y549183D01*
X1151143Y551224D01*
X1150706Y553266D01*
X1149396Y555016D01*
X1147867Y555599D01*
X1141099D01*
G01X1159254Y563766D02*
Y546266D01*
X1167988D01*
G01X1185488D02*
X1176754D01*
Y563766D01*
X1185488D01*
G01X1181994Y555308D02*
X1176754D01*
G01X1198621Y545683D02*
X1198184Y545974D01*
Y546558D01*
X1198621Y546849D01*
X1199058Y546558D01*
Y545974D01*
X1198621Y545683D01*
G01Y553557D02*
X1198184Y553849D01*
Y554433D01*
X1198621Y554724D01*
X1199058Y554433D01*
Y553849D01*
X1198621Y553557D01*
G01X1229254Y563766D02*
Y546266D01*
X1237988D01*
G01X1251121D02*
Y563766D01*
X1248501Y560266D01*
G01Y546266D02*
X1253741D01*
G01X924768Y407083D02*
X934374Y419916D01*
G01X929571Y422249D02*
Y404749D01*
G01X934374Y407083D02*
X924768Y419916D01*
G01X923021Y413499D02*
X936121D01*
G01X943359Y409707D02*
X944888Y408249D01*
X946634Y407666D01*
X948381Y408249D01*
X949909Y409999D01*
X951001Y412624D01*
X951438Y415249D01*
Y418457D01*
X951001Y421082D01*
X949909Y423416D01*
X948599Y424583D01*
X947071Y425166D01*
X945324Y424583D01*
X944014Y423416D01*
X943141Y421666D01*
X942704Y419332D01*
X943141Y417291D01*
X944233Y415249D01*
X945543Y414082D01*
X947071Y413791D01*
X948817Y414374D01*
X950128Y415833D01*
X951438Y418457D01*
G01X964134Y407666D02*
X964571Y411457D01*
X965226Y414666D01*
X966099Y417583D01*
X967191Y420791D01*
X968938Y425166D01*
X960204D01*
G01X982071Y407083D02*
X981634Y407374D01*
Y407958D01*
X982071Y408249D01*
X982508Y407958D01*
Y407374D01*
X982071Y407083D01*
G01X999571Y425166D02*
X997824Y424583D01*
X996514Y423124D01*
X995641Y421375D01*
X994986Y419041D01*
X994768Y416416D01*
X994986Y413791D01*
X995641Y411457D01*
X996514Y409707D01*
X997824Y408249D01*
X999571Y407666D01*
X1001317Y408249D01*
X1002628Y409707D01*
X1003501Y411457D01*
X1004156Y413791D01*
X1004374Y416416D01*
X1004156Y419041D01*
X1003501Y421375D01*
X1002628Y423124D01*
X1001317Y424583D01*
X999571Y425166D01*
G01X929571Y373016D02*
Y390516D01*
X926951Y387016D01*
G01Y373016D02*
X932191D01*
G01X947071Y390516D02*
X945324Y389933D01*
X944014Y388474D01*
X943141Y386725D01*
X942486Y384391D01*
X942268Y381766D01*
X942486Y379141D01*
X943141Y376807D01*
X944014Y375057D01*
X945324Y373599D01*
X947071Y373016D01*
X948817Y373599D01*
X950128Y375057D01*
X951001Y376807D01*
X951656Y379141D01*
X951874Y381766D01*
X951656Y384391D01*
X951001Y386725D01*
X950128Y388474D01*
X948817Y389933D01*
X947071Y390516D01*
G01X964571D02*
X962824Y389933D01*
X961514Y388474D01*
X960641Y386725D01*
X959986Y384391D01*
X959768Y381766D01*
X959986Y379141D01*
X960641Y376807D01*
X961514Y375057D01*
X962824Y373599D01*
X964571Y373016D01*
X966317Y373599D01*
X967628Y375057D01*
X968501Y376807D01*
X969156Y379141D01*
X969374Y381766D01*
X969156Y384391D01*
X968501Y386725D01*
X967628Y388474D01*
X966317Y389933D01*
X964571Y390516D01*
G01X982071Y372433D02*
X981634Y372724D01*
Y373308D01*
X982071Y373599D01*
X982508Y373308D01*
Y372724D01*
X982071Y372433D01*
G01X999571Y390516D02*
X997824Y389933D01*
X996514Y388474D01*
X995641Y386725D01*
X994986Y384391D01*
X994768Y381766D01*
X994986Y379141D01*
X995641Y376807D01*
X996514Y375057D01*
X997824Y373599D01*
X999571Y373016D01*
X1001317Y373599D01*
X1002628Y375057D01*
X1003501Y376807D01*
X1004156Y379141D01*
X1004374Y381766D01*
X1004156Y384391D01*
X1003501Y386725D01*
X1002628Y388474D01*
X1001317Y389933D01*
X999571Y390516D01*
G01X938321Y476966D02*
X939849Y477258D01*
X941596Y478132D01*
X942688Y479590D01*
X943124Y481633D01*
X942688Y483674D01*
X941378Y485424D01*
X939413Y486299D01*
X937229D01*
X935919Y486883D01*
X934827Y488341D01*
X934391Y490382D01*
X935046Y492424D01*
X936574Y493883D01*
X938321Y494466D01*
X940067Y493883D01*
X941596Y492424D01*
X942251Y490382D01*
X941814Y488341D01*
X940723Y486883D01*
X939413Y486299D01*
X937229D01*
X935264Y485424D01*
X933954Y483674D01*
X933518Y481633D01*
X933954Y479590D01*
X935046Y478132D01*
X936793Y477258D01*
X938321Y476966D01*
G01X951018Y479590D02*
X952327Y478132D01*
X953856Y477258D01*
X955821Y476966D01*
X957786Y477549D01*
X959314Y478716D01*
X960406Y480757D01*
X960624Y483091D01*
X960188Y485424D01*
X959096Y486883D01*
X957567Y488049D01*
X956039Y488341D01*
X954511Y488049D01*
X952546Y486883D01*
X953201Y494466D01*
X959096D01*
G01X973321Y476383D02*
X972884Y476674D01*
Y477258D01*
X973321Y477549D01*
X973758Y477258D01*
Y476674D01*
X973321Y476383D01*
G01X990821Y494466D02*
X989074Y493883D01*
X987764Y492424D01*
X986891Y490675D01*
X986236Y488341D01*
X986018Y485716D01*
X986236Y483091D01*
X986891Y480757D01*
X987764Y479007D01*
X989074Y477549D01*
X990821Y476966D01*
X992567Y477549D01*
X993878Y479007D01*
X994751Y480757D01*
X995406Y483091D01*
X995624Y485716D01*
X995406Y488341D01*
X994751Y490675D01*
X993878Y492424D01*
X992567Y493883D01*
X990821Y494466D01*
G01X924768Y441733D02*
X934374Y454566D01*
G01X929571Y456899D02*
Y439399D01*
G01X934374Y441733D02*
X924768Y454566D01*
G01X923021Y448149D02*
X936121D01*
G01X943359Y444357D02*
X944888Y442899D01*
X946634Y442316D01*
X948381Y442899D01*
X949909Y444649D01*
X951001Y447274D01*
X951438Y449899D01*
Y453107D01*
X951001Y455732D01*
X949909Y458066D01*
X948599Y459233D01*
X947071Y459816D01*
X945324Y459233D01*
X944014Y458066D01*
X943141Y456316D01*
X942704Y453982D01*
X943141Y451941D01*
X944233Y449899D01*
X945543Y448732D01*
X947071Y448441D01*
X948817Y449024D01*
X950128Y450483D01*
X951438Y453107D01*
G01X960423Y456899D02*
X961733Y458649D01*
X963261Y459524D01*
X965008Y459816D01*
X967191Y459233D01*
X968719Y457774D01*
X969156Y456025D01*
X968938Y454274D01*
X968064Y452816D01*
X963698Y449899D01*
X961733Y447858D01*
X960423Y444940D01*
X959986Y442316D01*
X969156D01*
G01X982071Y441733D02*
X981634Y442024D01*
Y442608D01*
X982071Y442899D01*
X982508Y442608D01*
Y442024D01*
X982071Y441733D01*
G01X999571Y459816D02*
X997824Y459233D01*
X996514Y457774D01*
X995641Y456025D01*
X994986Y453691D01*
X994768Y451066D01*
X994986Y448441D01*
X995641Y446107D01*
X996514Y444357D01*
X997824Y442899D01*
X999571Y442316D01*
X1001317Y442899D01*
X1002628Y444357D01*
X1003501Y446107D01*
X1004156Y448441D01*
X1004374Y451066D01*
X1004156Y453691D01*
X1003501Y456025D01*
X1002628Y457774D01*
X1001317Y459233D01*
X999571Y459816D01*
G01X900701Y529116D02*
X905941D01*
G01X903321D02*
Y511616D01*
G01X900701D02*
X905941D01*
G01X915144D02*
Y529116D01*
X920821Y514533D01*
X926498Y529116D01*
Y511616D01*
G01X933954D02*
Y529116D01*
X939194D01*
X940941Y528241D01*
X942251Y526199D01*
X942688Y523866D01*
X942251Y521533D01*
X941159Y519783D01*
X939194Y518907D01*
X933954D01*
G01X954729Y505783D02*
X952546Y508699D01*
X951454Y511616D01*
Y523282D01*
X952546Y526199D01*
X954729Y529116D01*
G01X973321Y511616D02*
X971574Y511908D01*
X970046Y513074D01*
X968736Y514824D01*
X967862Y516866D01*
X967426Y519199D01*
Y521533D01*
X967862Y523866D01*
X968736Y525908D01*
X970046Y527657D01*
X971574Y528824D01*
X973321Y529116D01*
X975067Y528824D01*
X976596Y527657D01*
X977906Y525908D01*
X978780Y523866D01*
X979216Y521533D01*
Y519199D01*
X978780Y516866D01*
X977906Y514824D01*
X976596Y513074D01*
X975067Y511908D01*
X973321Y511616D01*
G01X987109D02*
Y529116D01*
G01Y520658D02*
X988201Y522116D01*
X989293Y522991D01*
X991039Y523282D01*
X992349Y522991D01*
X993878Y521824D01*
X994533Y520074D01*
Y511616D01*
G01X1001771D02*
Y523282D01*
G01Y520074D02*
X1002426Y521533D01*
X1003518Y522699D01*
X1005046Y523282D01*
X1006574Y522699D01*
X1007666Y521533D01*
X1008321Y520074D01*
Y511616D01*
G01Y520074D02*
X1008976Y521533D01*
X1010067Y522699D01*
X1011596Y523282D01*
X1013124Y522699D01*
X1014216Y521533D01*
X1014871Y519783D01*
Y511616D01*
G01X1026913Y505783D02*
X1029096Y508699D01*
X1030188Y511616D01*
Y523282D01*
X1029096Y526199D01*
X1026913Y529116D01*
G01X1126018Y411166D02*
X1127327Y409124D01*
X1129074Y407958D01*
X1131039Y407666D01*
X1132786Y407958D01*
X1134533Y409416D01*
X1135624Y411166D01*
X1135843Y412916D01*
X1135406Y414957D01*
X1133878Y416416D01*
X1132349Y416999D01*
X1130384D01*
G01X1132349D02*
X1133659Y417874D01*
X1134751Y419332D01*
X1135188Y421082D01*
X1134751Y422833D01*
X1133659Y424291D01*
X1131694Y425166D01*
X1129729Y424874D01*
X1127764Y423707D01*
G01X1148321Y407083D02*
X1147884Y407374D01*
Y407958D01*
X1148321Y408249D01*
X1148758Y407958D01*
Y407374D01*
X1148321Y407083D01*
G01X1161018Y410290D02*
X1162327Y408832D01*
X1163856Y407958D01*
X1165821Y407666D01*
X1167786Y408249D01*
X1169314Y409416D01*
X1170406Y411457D01*
X1170624Y413791D01*
X1170188Y416124D01*
X1169096Y417583D01*
X1167567Y418749D01*
X1166039Y419041D01*
X1164511Y418749D01*
X1162546Y417583D01*
X1163201Y425166D01*
X1169096D01*
G01X1179391Y407083D02*
X1187251Y425166D01*
G01X1203441Y407666D02*
Y425166D01*
X1195362Y412624D01*
X1206280D01*
G01X1218321Y407083D02*
X1217884Y407374D01*
Y407958D01*
X1218321Y408249D01*
X1218758Y407958D01*
Y407374D01*
X1218321Y407083D01*
G01X1235821Y425166D02*
X1234074Y424583D01*
X1232764Y423124D01*
X1231891Y421375D01*
X1231236Y419041D01*
X1231018Y416416D01*
X1231236Y413791D01*
X1231891Y411457D01*
X1232764Y409707D01*
X1234074Y408249D01*
X1235821Y407666D01*
X1237567Y408249D01*
X1238878Y409707D01*
X1239751Y411457D01*
X1240406Y413791D01*
X1240624Y416416D01*
X1240406Y419041D01*
X1239751Y421375D01*
X1238878Y423124D01*
X1237567Y424583D01*
X1235821Y425166D01*
G01X1124691Y373016D02*
Y390516D01*
X1116612Y377974D01*
X1127530D01*
G01X1139571Y372433D02*
X1139134Y372724D01*
Y373308D01*
X1139571Y373599D01*
X1140008Y373308D01*
Y372724D01*
X1139571Y372433D01*
G01X1153359Y375057D02*
X1154888Y373599D01*
X1156634Y373016D01*
X1158381Y373599D01*
X1159909Y375349D01*
X1161001Y377974D01*
X1161438Y380599D01*
Y383807D01*
X1161001Y386432D01*
X1159909Y388766D01*
X1158599Y389933D01*
X1157071Y390516D01*
X1155324Y389933D01*
X1154014Y388766D01*
X1153141Y387016D01*
X1152704Y384682D01*
X1153141Y382641D01*
X1154233Y380599D01*
X1155543Y379432D01*
X1157071Y379141D01*
X1158817Y379724D01*
X1160128Y381183D01*
X1161438Y383807D01*
G01X1170641Y372433D02*
X1178501Y390516D01*
G01X1192071Y373016D02*
Y390516D01*
X1189451Y387016D01*
G01Y373016D02*
X1194691D01*
G01X1209571D02*
Y390516D01*
X1206951Y387016D01*
G01Y373016D02*
X1212191D01*
G01X1227071Y372433D02*
X1226634Y372724D01*
Y373308D01*
X1227071Y373599D01*
X1227508Y373308D01*
Y372724D01*
X1227071Y372433D01*
G01X1244571Y373016D02*
Y390516D01*
X1241951Y387016D01*
G01Y373016D02*
X1247191D01*
G01X1117268Y479590D02*
X1118577Y478132D01*
X1120106Y477258D01*
X1122071Y476966D01*
X1124036Y477549D01*
X1125564Y478716D01*
X1126656Y480757D01*
X1126874Y483091D01*
X1126438Y485424D01*
X1125346Y486883D01*
X1123817Y488049D01*
X1122289Y488341D01*
X1120761Y488049D01*
X1118796Y486883D01*
X1119451Y494466D01*
X1125346D01*
G01X1139571Y476383D02*
X1139134Y476674D01*
Y477258D01*
X1139571Y477549D01*
X1140008Y477258D01*
Y476674D01*
X1139571Y476383D01*
G01X1156634Y476966D02*
X1157071Y480757D01*
X1157726Y483966D01*
X1158599Y486883D01*
X1159691Y490091D01*
X1161438Y494466D01*
X1152704D01*
G01X1169768Y479590D02*
X1171077Y478132D01*
X1172606Y477258D01*
X1174571Y476966D01*
X1176536Y477549D01*
X1178064Y478716D01*
X1179156Y480757D01*
X1179374Y483091D01*
X1178938Y485424D01*
X1177846Y486883D01*
X1176317Y488049D01*
X1174789Y488341D01*
X1173261Y488049D01*
X1171296Y486883D01*
X1171951Y494466D01*
X1177846D01*
G01X1188141Y476383D02*
X1196001Y494466D01*
G01X1205423Y484257D02*
X1206951Y486299D01*
X1208261Y487466D01*
X1210008Y488049D01*
X1211536Y487466D01*
X1212628Y486299D01*
X1213501Y484549D01*
X1213719Y482508D01*
X1213501Y480757D01*
X1212628Y479007D01*
X1211317Y477549D01*
X1209789Y476966D01*
X1208043Y477549D01*
X1206514Y479299D01*
X1205641Y481924D01*
X1205423Y484841D01*
X1205859Y488632D01*
X1206514Y490675D01*
X1207606Y492716D01*
X1209134Y494174D01*
X1210663Y494466D01*
X1212191Y493883D01*
X1213283Y492424D01*
G01X1227071Y476383D02*
X1226634Y476674D01*
Y477258D01*
X1227071Y477549D01*
X1227508Y477258D01*
Y476674D01*
X1227071Y476383D01*
G01X1239768Y479590D02*
X1241077Y478132D01*
X1242606Y477258D01*
X1244571Y476966D01*
X1246536Y477549D01*
X1248064Y478716D01*
X1249156Y480757D01*
X1249374Y483091D01*
X1248938Y485424D01*
X1247846Y486883D01*
X1246317Y488049D01*
X1244789Y488341D01*
X1243261Y488049D01*
X1241296Y486883D01*
X1241951Y494466D01*
X1247846D01*
G01X1117268Y445816D02*
X1118577Y443774D01*
X1120324Y442608D01*
X1122289Y442316D01*
X1124036Y442608D01*
X1125783Y444066D01*
X1126874Y445816D01*
X1127093Y447566D01*
X1126656Y449607D01*
X1125128Y451066D01*
X1123599Y451649D01*
X1121634D01*
G01X1123599D02*
X1124909Y452524D01*
X1126001Y453982D01*
X1126438Y455732D01*
X1126001Y457483D01*
X1124909Y458941D01*
X1122944Y459816D01*
X1120979Y459524D01*
X1119014Y458357D01*
G01X1139571Y441733D02*
X1139134Y442024D01*
Y442608D01*
X1139571Y442899D01*
X1140008Y442608D01*
Y442024D01*
X1139571Y441733D01*
G01X1156634Y442316D02*
X1157071Y446107D01*
X1157726Y449316D01*
X1158599Y452233D01*
X1159691Y455441D01*
X1161438Y459816D01*
X1152704D01*
G01X1169768Y444940D02*
X1171077Y443482D01*
X1172606Y442608D01*
X1174571Y442316D01*
X1176536Y442899D01*
X1178064Y444066D01*
X1179156Y446107D01*
X1179374Y448441D01*
X1178938Y450774D01*
X1177846Y452233D01*
X1176317Y453399D01*
X1174789Y453691D01*
X1173261Y453399D01*
X1171296Y452233D01*
X1171951Y459816D01*
X1177846D01*
G01X1188141Y441733D02*
X1196001Y459816D01*
G01X1204768Y445816D02*
X1206077Y443774D01*
X1207824Y442608D01*
X1209789Y442316D01*
X1211536Y442608D01*
X1213283Y444066D01*
X1214374Y445816D01*
X1214593Y447566D01*
X1214156Y449607D01*
X1212628Y451066D01*
X1211099Y451649D01*
X1209134D01*
G01X1211099D02*
X1212409Y452524D01*
X1213501Y453982D01*
X1213938Y455732D01*
X1213501Y457483D01*
X1212409Y458941D01*
X1210444Y459816D01*
X1208479Y459524D01*
X1206514Y458357D01*
G01X1227071Y441733D02*
X1226634Y442024D01*
Y442608D01*
X1227071Y442899D01*
X1227508Y442608D01*
Y442024D01*
X1227071Y441733D01*
G01X1239768Y444940D02*
X1241077Y443482D01*
X1242606Y442608D01*
X1244571Y442316D01*
X1246536Y442899D01*
X1248064Y444066D01*
X1249156Y446107D01*
X1249374Y448441D01*
X1248938Y450774D01*
X1247846Y452233D01*
X1246317Y453399D01*
X1244789Y453691D01*
X1243261Y453399D01*
X1241296Y452233D01*
X1241951Y459816D01*
X1247846D01*
G01X1089271Y529116D02*
X1092327Y511616D01*
X1095821Y529116D01*
X1099314Y511616D01*
X1102371Y529116D01*
G01X1110701D02*
X1115941D01*
G01X1113321D02*
Y511616D01*
G01X1110701D02*
X1115941D01*
G01X1126018D02*
Y529116D01*
X1130384D01*
X1132131Y528241D01*
X1133441Y527074D01*
X1134533Y525325D01*
X1135406Y523282D01*
X1135624Y520366D01*
X1135406Y517449D01*
X1134533Y515407D01*
X1133441Y513657D01*
X1132131Y512491D01*
X1130384Y511616D01*
X1126018D01*
G01X1148321Y529116D02*
Y511616D01*
G01X1143299Y529116D02*
X1153343D01*
G01X1161236Y511616D02*
Y529116D01*
G01X1170406D02*
Y511616D01*
G01Y520366D02*
X1161236D01*
G01X1182229Y505783D02*
X1180046Y508699D01*
X1178954Y511616D01*
Y523282D01*
X1180046Y526199D01*
X1182229Y529116D01*
G01X1194271Y511616D02*
Y523282D01*
G01Y520074D02*
X1194926Y521533D01*
X1196018Y522699D01*
X1197546Y523282D01*
X1199074Y522699D01*
X1200166Y521533D01*
X1200821Y520074D01*
Y511616D01*
G01Y520074D02*
X1201476Y521533D01*
X1202567Y522699D01*
X1204096Y523282D01*
X1205624Y522699D01*
X1206716Y521533D01*
X1207371Y519783D01*
Y511616D01*
G01X1218321Y523282D02*
Y511616D01*
G01Y527949D02*
X1217884Y528241D01*
Y528824D01*
X1218321Y529116D01*
X1218758Y528824D01*
Y528241D01*
X1218321Y527949D01*
G01X1235821Y511616D02*
Y529116D01*
G01X1250046Y513657D02*
X1251138Y512491D01*
X1252666Y511616D01*
X1253976D01*
X1255286Y512199D01*
X1256159Y513074D01*
X1256596Y514240D01*
X1256378Y515991D01*
X1255504Y516866D01*
X1251574Y518616D01*
X1250701Y520658D01*
X1251138Y522116D01*
X1252011Y522991D01*
X1253321Y523282D01*
X1254631Y522991D01*
X1255941Y522116D01*
G01X1271913Y505783D02*
X1274096Y508699D01*
X1275188Y511616D01*
Y523282D01*
X1274096Y526199D01*
X1271913Y529116D01*
G01X1353518Y407666D02*
Y425166D01*
X1357884D01*
X1359631Y424291D01*
X1360941Y423124D01*
X1362033Y421375D01*
X1362906Y419332D01*
X1363124Y416416D01*
X1362906Y413499D01*
X1362033Y411457D01*
X1360941Y409707D01*
X1359631Y408541D01*
X1357884Y407666D01*
X1353518D01*
G01X1371454D02*
Y425166D01*
X1376694D01*
X1378441Y424291D01*
X1379751Y422249D01*
X1380188Y419916D01*
X1379751Y417583D01*
X1378659Y415833D01*
X1376694Y414957D01*
X1371454D01*
G01X1353518Y373016D02*
Y390516D01*
X1357884D01*
X1359631Y389641D01*
X1360941Y388474D01*
X1362033Y386725D01*
X1362906Y384682D01*
X1363124Y381766D01*
X1362906Y378849D01*
X1362033Y376807D01*
X1360941Y375057D01*
X1359631Y373891D01*
X1357884Y373016D01*
X1353518D01*
G01X1371454D02*
Y390516D01*
X1376694D01*
X1378441Y389641D01*
X1379751Y387599D01*
X1380188Y385266D01*
X1379751Y382933D01*
X1378659Y381183D01*
X1376694Y380307D01*
X1371454D01*
G01X1353518Y476966D02*
Y494466D01*
X1357884D01*
X1359631Y493591D01*
X1360941Y492424D01*
X1362033Y490675D01*
X1362906Y488632D01*
X1363124Y485716D01*
X1362906Y482799D01*
X1362033Y480757D01*
X1360941Y479007D01*
X1359631Y477841D01*
X1357884Y476966D01*
X1353518D01*
G01X1371454D02*
Y494466D01*
X1376694D01*
X1378441Y493591D01*
X1379751Y491549D01*
X1380188Y489216D01*
X1379751Y486883D01*
X1378659Y485133D01*
X1376694Y484257D01*
X1371454D01*
G01X1353518Y442316D02*
Y459816D01*
X1357884D01*
X1359631Y458941D01*
X1360941Y457774D01*
X1362033Y456025D01*
X1362906Y453982D01*
X1363124Y451066D01*
X1362906Y448149D01*
X1362033Y446107D01*
X1360941Y444357D01*
X1359631Y443191D01*
X1357884Y442316D01*
X1353518D01*
G01X1371454D02*
Y459816D01*
X1376694D01*
X1378441Y458941D01*
X1379751Y456899D01*
X1380188Y454566D01*
X1379751Y452233D01*
X1378659Y450483D01*
X1376694Y449607D01*
X1371454D01*
G01X1340821Y529116D02*
Y511616D01*
G01X1335799Y529116D02*
X1345843D01*
G01X1358321Y511616D02*
Y519491D01*
X1353954Y529116D01*
G01X1362688D02*
X1358321Y519491D01*
G01X1371454Y511616D02*
Y529116D01*
X1376694D01*
X1378441Y528241D01*
X1379751Y526199D01*
X1380188Y523866D01*
X1379751Y521533D01*
X1378659Y519783D01*
X1376694Y518907D01*
X1371454D01*
G01X1397688Y511616D02*
X1388954D01*
Y529116D01*
X1397688D01*
G01X1394194Y520658D02*
X1388954D01*
G01X1441454Y511616D02*
Y529116D01*
X1446913D01*
X1448659Y528241D01*
X1449751Y527074D01*
X1450188Y524741D01*
X1449751Y522407D01*
X1448441Y520949D01*
X1446913Y520074D01*
X1441454D01*
G01X1446913D02*
X1450188Y511616D01*
G01X1460046Y519491D02*
X1467033D01*
X1466378Y521533D01*
X1465286Y522699D01*
X1463758Y523282D01*
X1462229Y522991D01*
X1460919Y522116D01*
X1460046Y520074D01*
X1459609Y518324D01*
Y516574D01*
X1460046Y514824D01*
X1461138Y513074D01*
X1462448Y511908D01*
X1463976Y511616D01*
X1465504Y512199D01*
X1467033Y513949D01*
G01X1479511Y511616D02*
Y526491D01*
X1479948Y527949D01*
X1480821Y528824D01*
X1482131Y529116D01*
X1483441Y528533D01*
X1484096Y527074D01*
G01X1481476Y522116D02*
X1477109D01*
G01X1498321Y511033D02*
X1497884Y511324D01*
Y511908D01*
X1498321Y512199D01*
X1498758Y511908D01*
Y511324D01*
X1498321Y511033D01*
G01X1528954Y511616D02*
Y529116D01*
X1534194D01*
X1535941Y528241D01*
X1537251Y526199D01*
X1537688Y523866D01*
X1537251Y521533D01*
X1536159Y519783D01*
X1534194Y518907D01*
X1528954D01*
G01X1550821Y511616D02*
Y529116D01*
G01X1572251Y511616D02*
Y523282D01*
G01Y521241D02*
X1571378Y522407D01*
X1570067Y522991D01*
X1568539Y523282D01*
X1567011Y522699D01*
X1565701Y521533D01*
X1564827Y519783D01*
X1564391Y517449D01*
X1564827Y515116D01*
X1565701Y513366D01*
X1567011Y512199D01*
X1568539Y511616D01*
X1570067Y511908D01*
X1571378Y512782D01*
X1572251Y513949D01*
G01X1582109Y511616D02*
Y523282D01*
G01Y520366D02*
X1582983Y521824D01*
X1584293Y522991D01*
X1586039Y523282D01*
X1587567Y522991D01*
X1588878Y521824D01*
X1589533Y519783D01*
Y511616D01*
G01X1600046Y519491D02*
X1607033D01*
X1606378Y521533D01*
X1605286Y522699D01*
X1603758Y523282D01*
X1602229Y522991D01*
X1600919Y522116D01*
X1600046Y520074D01*
X1599609Y518324D01*
Y516574D01*
X1600046Y514824D01*
X1601138Y513074D01*
X1602448Y511908D01*
X1603976Y511616D01*
X1605504Y512199D01*
X1607033Y513949D01*
G01X1511454Y425166D02*
Y407666D01*
X1520188D01*
G01X1529173Y422249D02*
X1530483Y423999D01*
X1532011Y424874D01*
X1533758Y425166D01*
X1535941Y424583D01*
X1537469Y423124D01*
X1537906Y421375D01*
X1537688Y419624D01*
X1536814Y418166D01*
X1532448Y415249D01*
X1530483Y413208D01*
X1529173Y410290D01*
X1528736Y407666D01*
X1537906D01*
G01X1511454Y390516D02*
Y373016D01*
X1520188D01*
G01X1529173Y387599D02*
X1530483Y389349D01*
X1532011Y390224D01*
X1533758Y390516D01*
X1535941Y389933D01*
X1537469Y388474D01*
X1537906Y386725D01*
X1537688Y384974D01*
X1536814Y383516D01*
X1532448Y380599D01*
X1530483Y378558D01*
X1529173Y375640D01*
X1528736Y373016D01*
X1537906D01*
G01X1511454Y494466D02*
Y476966D01*
X1520188D01*
G01X1529173Y491549D02*
X1530483Y493299D01*
X1532011Y494174D01*
X1533758Y494466D01*
X1535941Y493883D01*
X1537469Y492424D01*
X1537906Y490675D01*
X1537688Y488924D01*
X1536814Y487466D01*
X1532448Y484549D01*
X1530483Y482508D01*
X1529173Y479590D01*
X1528736Y476966D01*
X1537906D01*
G01X1511454Y459816D02*
Y442316D01*
X1520188D01*
G01X1529173Y456899D02*
X1530483Y458649D01*
X1532011Y459524D01*
X1533758Y459816D01*
X1535941Y459233D01*
X1537469Y457774D01*
X1537906Y456025D01*
X1537688Y454274D01*
X1536814Y452816D01*
X1532448Y449899D01*
X1530483Y447858D01*
X1529173Y444940D01*
X1528736Y442316D01*
X1537906D01*
G01X1721121Y488632D02*
Y476966D01*
G01Y493299D02*
X1720684Y493591D01*
Y494174D01*
X1721121Y494466D01*
X1721558Y494174D01*
Y493591D01*
X1721121Y493299D01*
G01X1735346Y479007D02*
X1736438Y477841D01*
X1737966Y476966D01*
X1739276D01*
X1740586Y477549D01*
X1741459Y478424D01*
X1741896Y479590D01*
X1741678Y481341D01*
X1740804Y482216D01*
X1736874Y483966D01*
X1736001Y486008D01*
X1736438Y487466D01*
X1737311Y488341D01*
X1738621Y488632D01*
X1739931Y488341D01*
X1741241Y487466D01*
G01X1768599Y476966D02*
Y494466D01*
X1778643Y476966D01*
Y494466D01*
G01X1791121Y476966D02*
X1789374Y477258D01*
X1787846Y478424D01*
X1786536Y480174D01*
X1785662Y482216D01*
X1785226Y484549D01*
Y486883D01*
X1785662Y489216D01*
X1786536Y491258D01*
X1787846Y493007D01*
X1789374Y494174D01*
X1791121Y494466D01*
X1792867Y494174D01*
X1794396Y493007D01*
X1795706Y491258D01*
X1796580Y489216D01*
X1797016Y486883D01*
Y484549D01*
X1796580Y482216D01*
X1795706Y480174D01*
X1794396Y478424D01*
X1792867Y477258D01*
X1791121Y476966D01*
G01X1808621Y494466D02*
Y476966D01*
G01X1803599Y494466D02*
X1813643D01*
G01X1839909Y488632D02*
Y480466D01*
X1840783Y478424D01*
X1842093Y477258D01*
X1843621Y476966D01*
X1845149Y477258D01*
X1846459Y478424D01*
X1847333Y480466D01*
G01Y476966D02*
Y488632D01*
G01X1857846Y479007D02*
X1858938Y477841D01*
X1860466Y476966D01*
X1861776D01*
X1863086Y477549D01*
X1863959Y478424D01*
X1864396Y479590D01*
X1864178Y481341D01*
X1863304Y482216D01*
X1859374Y483966D01*
X1858501Y486008D01*
X1858938Y487466D01*
X1859811Y488341D01*
X1861121Y488632D01*
X1862431Y488341D01*
X1863741Y487466D01*
G01X1875346Y484841D02*
X1882333D01*
X1881678Y486883D01*
X1880586Y488049D01*
X1879058Y488632D01*
X1877529Y488341D01*
X1876219Y487466D01*
X1875346Y485424D01*
X1874909Y483674D01*
Y481924D01*
X1875346Y480174D01*
X1876438Y478424D01*
X1877748Y477258D01*
X1879276Y476966D01*
X1880804Y477549D01*
X1882333Y479299D01*
G01X1900051Y494466D02*
Y476966D01*
G01Y479590D02*
X1899178Y478132D01*
X1897867Y477258D01*
X1896339Y476966D01*
X1894593Y477549D01*
X1893283Y479007D01*
X1892409Y480757D01*
X1892191Y482799D01*
X1892409Y484841D01*
X1893283Y486591D01*
X1894593Y488049D01*
X1896339Y488632D01*
X1897867Y488341D01*
X1898959Y487757D01*
X1900051Y486591D01*
G01X1646318Y511033D02*
X1655924Y523866D01*
G01X1651121Y526199D02*
Y508699D01*
G01X1655924Y511033D02*
X1646318Y523866D01*
G01X1644571Y517449D02*
X1657671D01*
G01X1683283D02*
X1688959D01*
G01X1716318Y511616D02*
Y529116D01*
X1720684D01*
X1722431Y528241D01*
X1723741Y527074D01*
X1724833Y525325D01*
X1725706Y523282D01*
X1725924Y520366D01*
X1725706Y517449D01*
X1724833Y515407D01*
X1723741Y513657D01*
X1722431Y512491D01*
X1720684Y511616D01*
X1716318D01*
G01X1735346Y519491D02*
X1742333D01*
X1741678Y521533D01*
X1740586Y522699D01*
X1739058Y523282D01*
X1737529Y522991D01*
X1736219Y522116D01*
X1735346Y520074D01*
X1734909Y518324D01*
Y516574D01*
X1735346Y514824D01*
X1736438Y513074D01*
X1737748Y511908D01*
X1739276Y511616D01*
X1740804Y512199D01*
X1742333Y513949D01*
G01X1752409Y511616D02*
Y523282D01*
G01Y520366D02*
X1753283Y521824D01*
X1754593Y522991D01*
X1756339Y523282D01*
X1757867Y522991D01*
X1759178Y521824D01*
X1759833Y519783D01*
Y511616D01*
G01X1773621D02*
X1772311Y511908D01*
X1771001Y513074D01*
X1770127Y515116D01*
X1769691Y517449D01*
X1770127Y519783D01*
X1771001Y521824D01*
X1772311Y522991D01*
X1773621Y523282D01*
X1774931Y522991D01*
X1776241Y521824D01*
X1777114Y519783D01*
X1777333Y517449D01*
X1777114Y515116D01*
X1776241Y513074D01*
X1774931Y511908D01*
X1773621Y511616D01*
G01X1791121Y529116D02*
Y511616D01*
G01X1788064Y523282D02*
X1794178D01*
G01X1805346Y519491D02*
X1812333D01*
X1811678Y521533D01*
X1810586Y522699D01*
X1809058Y523282D01*
X1807529Y522991D01*
X1806219Y522116D01*
X1805346Y520074D01*
X1804909Y518324D01*
Y516574D01*
X1805346Y514824D01*
X1806438Y513074D01*
X1807748Y511908D01*
X1809276Y511616D01*
X1810804Y512199D01*
X1812333Y513949D01*
G01X1822846Y513657D02*
X1823938Y512491D01*
X1825466Y511616D01*
X1826776D01*
X1828086Y512199D01*
X1828959Y513074D01*
X1829396Y514240D01*
X1829178Y515991D01*
X1828304Y516866D01*
X1824374Y518616D01*
X1823501Y520658D01*
X1823938Y522116D01*
X1824811Y522991D01*
X1826121Y523282D01*
X1827431Y522991D01*
X1828741Y522116D01*
G01X1861121Y529116D02*
Y511616D01*
G01X1858064Y523282D02*
X1864178D01*
G01X1874909Y511616D02*
Y529116D01*
G01Y520658D02*
X1876001Y522116D01*
X1877093Y522991D01*
X1878839Y523282D01*
X1880149Y522991D01*
X1881678Y521824D01*
X1882333Y520074D01*
Y511616D01*
G01X1900051D02*
Y523282D01*
G01Y521241D02*
X1899178Y522407D01*
X1897867Y522991D01*
X1896339Y523282D01*
X1894811Y522699D01*
X1893501Y521533D01*
X1892627Y519783D01*
X1892191Y517449D01*
X1892627Y515116D01*
X1893501Y513366D01*
X1894811Y512199D01*
X1896339Y511616D01*
X1897867Y511908D01*
X1899178Y512782D01*
X1900051Y513949D01*
G01X1913621Y529116D02*
Y511616D01*
G01X1910564Y523282D02*
X1916678D01*
G01X1948621Y529116D02*
Y511616D01*
G01X1945564Y523282D02*
X1951678D01*
G01X1962409Y511616D02*
Y529116D01*
G01Y520658D02*
X1963501Y522116D01*
X1964593Y522991D01*
X1966339Y523282D01*
X1967649Y522991D01*
X1969178Y521824D01*
X1969833Y520074D01*
Y511616D01*
G01X1983621Y523282D02*
Y511616D01*
G01Y527949D02*
X1983184Y528241D01*
Y528824D01*
X1983621Y529116D01*
X1984058Y528824D01*
Y528241D01*
X1983621Y527949D01*
G01X1997846Y513657D02*
X1998938Y512491D01*
X2000466Y511616D01*
X2001776D01*
X2003086Y512199D01*
X2003959Y513074D01*
X2004396Y514240D01*
X2004178Y515991D01*
X2003304Y516866D01*
X1999374Y518616D01*
X1998501Y520658D01*
X1998938Y522116D01*
X1999811Y522991D01*
X2001121Y523282D01*
X2002431Y522991D01*
X2003741Y522116D01*
G01X2033501Y529116D02*
X2038741D01*
G01X2036121D02*
Y511616D01*
G01X2033501D02*
X2038741D01*
G01X2047071D02*
Y523282D01*
G01Y520074D02*
X2047726Y521533D01*
X2048818Y522699D01*
X2050346Y523282D01*
X2051874Y522699D01*
X2052966Y521533D01*
X2053621Y520074D01*
Y511616D01*
G01Y520074D02*
X2054276Y521533D01*
X2055367Y522699D01*
X2056896Y523282D01*
X2058424Y522699D01*
X2059516Y521533D01*
X2060171Y519783D01*
Y511616D01*
G01X2067191Y505783D02*
Y523282D01*
G01Y520658D02*
X2068283Y522116D01*
X2069374Y522991D01*
X2071121Y523282D01*
X2072649Y522991D01*
X2074178Y521533D01*
X2074833Y519491D01*
X2075051Y517449D01*
X2074833Y515407D01*
X2074178Y513366D01*
X2072867Y512199D01*
X2071121Y511616D01*
X2069593Y511908D01*
X2068064Y512782D01*
X2067191Y513949D01*
G01X2085346Y519491D02*
X2092333D01*
X2091678Y521533D01*
X2090586Y522699D01*
X2089058Y523282D01*
X2087529Y522991D01*
X2086219Y522116D01*
X2085346Y520074D01*
X2084909Y518324D01*
Y516574D01*
X2085346Y514824D01*
X2086438Y513074D01*
X2087748Y511908D01*
X2089276Y511616D01*
X2090804Y512199D01*
X2092333Y513949D01*
G01X2110051Y529116D02*
Y511616D01*
G01Y514240D02*
X2109178Y512782D01*
X2107867Y511908D01*
X2106339Y511616D01*
X2104593Y512199D01*
X2103283Y513657D01*
X2102409Y515407D01*
X2102191Y517449D01*
X2102409Y519491D01*
X2103283Y521241D01*
X2104593Y522699D01*
X2106339Y523282D01*
X2107867Y522991D01*
X2108959Y522407D01*
X2110051Y521241D01*
G01X2127551Y511616D02*
Y523282D01*
G01Y521241D02*
X2126678Y522407D01*
X2125367Y522991D01*
X2123839Y523282D01*
X2122311Y522699D01*
X2121001Y521533D01*
X2120127Y519783D01*
X2119691Y517449D01*
X2120127Y515116D01*
X2121001Y513366D01*
X2122311Y512199D01*
X2123839Y511616D01*
X2125367Y511908D01*
X2126678Y512782D01*
X2127551Y513949D01*
G01X2137409Y511616D02*
Y523282D01*
G01Y520366D02*
X2138283Y521824D01*
X2139593Y522991D01*
X2141339Y523282D01*
X2142867Y522991D01*
X2144178Y521824D01*
X2144833Y519783D01*
Y511616D01*
G01X2162114Y521824D02*
X2160586Y522991D01*
X2159276Y523282D01*
X2157529Y522699D01*
X2156219Y521533D01*
X2155346Y519491D01*
X2155127Y517449D01*
X2155346Y515407D01*
X2156219Y513657D01*
X2157529Y512199D01*
X2159276Y511616D01*
X2160804Y512199D01*
X2162114Y513366D01*
G01X2172846Y519491D02*
X2179833D01*
X2179178Y521533D01*
X2178086Y522699D01*
X2176558Y523282D01*
X2175029Y522991D01*
X2173719Y522116D01*
X2172846Y520074D01*
X2172409Y518324D01*
Y516574D01*
X2172846Y514824D01*
X2173938Y513074D01*
X2175248Y511908D01*
X2176776Y511616D01*
X2178304Y512199D01*
X2179833Y513949D01*
G01X20103Y-86244D02*
G03I-4291J0D01*
G01X0Y-87362D02*
G03X15000Y-102362I15000J0D01*
G01X0Y-11811D02*
Y-87362D01*
G01X3937Y-7874D02*
G03X0Y-11811I0J-3937D01*
G01X15748Y-7874D02*
X3937D01*
G01X0Y7874D02*
G03X7874Y0I7874J0D01*
G01X818897D02*
X7874D01*
G01X0Y7874D02*
Y562992D01*
G01X7874Y570866D02*
G03X0Y562992I0J-7874D01*
G01X7874Y570866D02*
X326781D01*
G01X312004Y-102362D02*
X15000D01*
G01X46456Y0D02*
G03Y-7874I0J-3937D01*
G01X15748D02*
G03Y0I0J3937D01*
G01X287400Y-7874D02*
X46456D01*
G01X40452Y499724D02*
G03I-3051J0D01*
G01X41535Y535157D02*
G03I-4134J0D01*
G01X44685Y517441D02*
G03I-7284J0D01*
G01X121082Y39055D02*
G03I-5019J0D01*
G01X120807Y14567D02*
G03I-4744J0D01*
G01X319878Y-102362D02*
G03X312004I-3937J0D01*
G01X811771D02*
X319878D01*
G01X326770Y0D02*
G03Y-7874I0J-3937D01*
G01X287400D02*
G03Y0I0J3937D01*
G01X302165Y531496D02*
G03I-6890J0D01*
G01X597707Y-7874D02*
X326770D01*
G01X379921Y156220D02*
G03I-5906J0D01*
G01X342529Y530315D02*
G03X334655I-3937J0D01*
G01X342529Y520720D02*
G03X352474Y509057I11811J0D01*
G01X334655Y520720D02*
G03X351230Y501282I19685J0D01*
G01X384484Y503937D02*
X352475Y509057D01*
G01X383858Y496063D02*
X351231Y501282D01*
G01X442287Y503937D02*
X384484D01*
G01X442913Y496063D02*
X383858D01*
G01X342529Y530315D02*
Y520720D01*
G01X334655Y562992D02*
Y520720D01*
G01X346466Y570866D02*
G03X342529Y566929I0J-3937D01*
G01X334655Y555512D02*
G03X342529I3937J0D01*
G01X346466Y570866D02*
X480325D01*
G01X334655Y562992D02*
G03X326781Y570866I-7874J0D01*
G01X342529Y566929D02*
Y555512D01*
G01X415943Y539991D02*
G03I-4291J0D01*
G01X474316Y509060D02*
X442287Y503937D01*
G01X475560Y501285D02*
X442913Y496063D01*
G01X492136Y530315D02*
G03X484262I-3937J0D01*
G01X474316Y509060D02*
G03X484262Y520723I-1865J11663D01*
G01X475560Y501285D02*
G03X492136Y520723I-3109J19438D01*
G01X484262Y530315D02*
Y520723D01*
G01X492136Y562992D02*
Y520723D01*
G01X484262Y566929D02*
G03X480325Y570866I-3937J0D01*
G01X484262Y555512D02*
G03X492136I3937J0D01*
G01X500010Y570866D02*
G03X492136Y562992I0J-7874D01*
G01X500010Y570866D02*
X818897D01*
G01X484262Y566929D02*
Y555512D01*
G01X537401Y371299D02*
G03I-5905J0D01*
G01X538386Y531496D02*
G03I-6890J0D01*
G01X628416Y0D02*
G03Y-7874I0J-3937D01*
G01X597707D02*
G03Y0I0J3937D01*
G01X780315Y-7874D02*
X628416D01*
G01X602362Y116141D02*
G03I-5906J0D01*
G01X817003Y-86834D02*
G03I-4292J0D01*
G01X811771Y-102362D02*
G03X826771Y-87362I0J15000D01*
G01X811023Y0D02*
G03Y-7874I0J-3937D01*
G01X780315D02*
G03Y0I0J3937D01*
G01X822834Y-7874D02*
X811023D01*
G01X818897Y0D02*
G03X826771Y7874I0J7874D01*
G01X818897Y0D02*
X807086D01*
G01X787401Y198819D02*
G03I-5905J0D01*
G01X792421Y499724D02*
G03I-3051J0D01*
G01X793504Y535157D02*
G03I-4134J0D01*
G01X796653Y517441D02*
G03I-7283J0D01*
G01X826771Y562992D02*
G03X818897Y570866I-7874J0D01*
G01X826771Y-11811D02*
Y-87362D01*
G01Y-11811D02*
G03X822834Y-7874I-3937J0D01*
G01X826771Y562992D02*
Y7874D01*
G54D12*
G01X504319Y171711D02*
Y173296D01*
G01X505919Y172185D02*
Y173144D01*
G01X511866Y160087D02*
X504319Y171711D01*
G01X513023Y161244D02*
X505919Y172185D01*
G01D02*
Y173144D01*
G01X504319Y171711D02*
Y173296D01*
G01X513023Y161244D02*
X505919Y172185D01*
G01X511866Y160087D02*
X504319Y171711D01*
G01X522820Y147511D02*
X504913Y159139D01*
G01X503756Y157982D02*
X512994Y151983D01*
G01X504913Y159139D02*
X504914D01*
G01X522820Y147511D02*
X504913Y159139D01*
G01X494710Y171924D02*
X503756Y157982D01*
G01X504914Y159139D02*
X496310Y172398D01*
G01X494710Y173117D02*
Y171924D01*
G01X496310Y172398D02*
Y173381D01*
G01Y172398D02*
Y173381D01*
G01X494710Y173117D02*
Y171924D01*
G01X504914Y159139D02*
X496310Y172398D01*
G01X494710Y171924D02*
X503756Y157982D01*
G01X504913Y159139D02*
X504914D01*
G01X503756Y157982D02*
X512994Y151983D01*
G01X522820Y147511D02*
X504913Y159139D01*
G01X503756Y157982D02*
X512994Y151983D01*
G01X513336Y181881D02*
X510864D01*
G01X513336Y183481D02*
X510864D01*
G01X513336D02*
X510864D01*
G01X513336Y181881D02*
X510864D01*
G01X504295Y180567D02*
Y179004D01*
G01X505895Y180567D02*
Y179004D01*
G01X503893Y181538D02*
G02X504295Y180567I-972J-971D01*
G01X505024Y182670D02*
G02X505895Y180567I-2103J-2103D01*
G01X502924Y183539D02*
G02X505024Y182670I0J-2972D01*
G01X502924Y181939D02*
G02X503893Y181538I0J-1371D01*
G01X505024Y182670D02*
G02X505895Y180567I-2103J-2103D01*
G01X502924Y183539D02*
G02X505024Y182670I0J-2972D01*
G01X500739Y181939D02*
X502924D01*
G01X500739Y183539D02*
X502924D01*
G01X505895Y180567D02*
Y179004D01*
G01X504295Y180567D02*
Y179004D01*
G01X505024Y182670D02*
G02X505895Y180567I-2103J-2103D01*
G01X503893Y181538D02*
G02X504295Y180567I-972J-971D01*
G01X502924Y181939D02*
G02X503893Y181538I0J-1371D01*
G01X502924Y183539D02*
G02X505024Y182670I0J-2972D01*
G01X503893Y181538D02*
G02X504295Y180567I-972J-971D01*
G01X502924Y181939D02*
G02X503893Y181538I0J-1371D01*
G01X500739Y183539D02*
X502924D01*
G01X500739Y181939D02*
X502924D01*
G01X494549Y180921D02*
Y179062D01*
G01X496149Y180922D02*
Y179062D01*
G01X494317Y181479D02*
G02X494549Y180921I-557J-559D01*
G01X495448Y182611D02*
G02X496149Y180922I-1688J-1691D01*
G01X493270Y181997D02*
G02X494174Y181622I0J-1278D01*
G01X493271Y183597D02*
G02X495306Y182753I-1J-2878D01*
G01X491314Y181997D02*
X493270D01*
G01X491314Y183597D02*
X493271D01*
G01X496149Y180922D02*
Y179062D01*
G01X494549Y180921D02*
Y179062D01*
G01X495448Y182611D02*
G02X496149Y180922I-1688J-1691D01*
G01X494317Y181479D02*
G02X494549Y180921I-557J-559D01*
G01X493271Y183597D02*
G02X495306Y182753I-1J-2878D01*
G01X493270Y181997D02*
G02X494174Y181622I0J-1278D01*
G01X491314Y183597D02*
X493271D01*
G01X491314Y181997D02*
X493270D01*
G01X577304Y106342D02*
X558676Y118440D01*
G01X578082Y107745D02*
X559833Y119597D01*
G01X578082Y107745D02*
X559833Y119597D01*
G01X577304Y106342D02*
X558676Y118440D01*
G01X566339Y107523D02*
X554983Y114899D01*
G01X578282Y101673D02*
X556141Y116056D01*
G01X571874Y103927D02*
X566339Y107523D01*
G01X578282Y101673D02*
X556141Y116056D01*
G01X577659Y100169D02*
X571874Y103927D01*
G01X578282Y101673D02*
X556141Y116056D01*
G01X578282Y101673D02*
X556141Y116056D01*
G01X566339Y107523D02*
X554983Y114899D01*
G01X571874Y103927D02*
X566339Y107523D01*
G01X577659Y100169D02*
X571874Y103927D01*
G01X549116Y112913D02*
X536031Y133068D01*
G01X562448Y104258D02*
X549116Y112913D01*
G01X576367Y97129D02*
X550273Y114070D01*
G01X575744Y95625D02*
X562448Y104258D01*
G01X576367Y97129D02*
X550273Y114070D01*
G01X549116Y112913D02*
X536031Y133068D01*
G01X576367Y97129D02*
X550273Y114070D01*
G01X562448Y104258D02*
X549116Y112913D01*
G01X575744Y95625D02*
X562448Y104258D01*
G01X566651Y95742D02*
X573797Y91099D01*
G01X574420Y92603D02*
X546835Y110526D01*
G01X559755Y100223D02*
X566651Y95742D01*
G01X574420Y92603D02*
X546835Y110526D01*
G01X545678Y109369D02*
X559755Y100223D01*
G01X574420Y92603D02*
X546835Y110526D01*
G01X533670Y127862D02*
X545678Y109369D01*
G01X546835Y110526D02*
X522820Y147511D01*
G01X546835Y110526D02*
X522820Y147511D01*
G01X546835Y110526D02*
X522820Y147511D01*
G01X533670Y127862D02*
X545678Y109369D01*
G01X574420Y92603D02*
X546835Y110526D01*
G01X566651Y95742D02*
X573797Y91099D01*
G01X559755Y100223D02*
X566651Y95742D01*
G01X545678Y109369D02*
X559755Y100223D01*
G01X557762Y170314D02*
X529016Y214582D01*
G01X556605Y169157D02*
X527859Y213425D01*
G01X561353Y167982D02*
X557762Y170314D01*
G01X573422Y158235D02*
X556605Y169157D01*
G01X565597Y165226D02*
X564364Y166027D01*
G01X573422Y158235D02*
X556605Y169157D01*
G01X574044Y159739D02*
X568608Y163270D01*
G01X573422Y158235D02*
X556605Y169157D01*
G01X557098Y150241D02*
X574644Y138848D01*
G01X557098Y150241D02*
X574644Y138848D01*
G01X569789Y143909D02*
X571022Y143108D01*
G01X557098Y150241D02*
X574644Y138848D01*
G01X565545Y146665D02*
X566778Y145864D01*
G01X557098Y150241D02*
X574644Y138848D01*
G01X558255Y151398D02*
X562534Y148620D01*
G01X557098Y150241D02*
X574644Y138848D01*
G01X523192Y205388D02*
X558255Y151398D01*
G01X522035Y204231D02*
X557098Y150241D01*
G01X558387Y142377D02*
X522429Y197655D01*
G01X565645Y128281D02*
X521269Y196503D01*
G01X561283Y137924D02*
X560481Y139156D01*
G01X565645Y128281D02*
X521269Y196503D01*
G01X564042Y133682D02*
X563240Y134914D01*
G01X565645Y128281D02*
X521269Y196503D01*
G01X566801Y129440D02*
X565999Y130672D01*
G01X565645Y128281D02*
X521269Y196503D01*
G01X567493Y128992D02*
X566801Y129440D01*
G01X566870Y127488D02*
X565645Y128281D01*
G01X568513Y128774D02*
X567493Y128992D01*
G01X568510Y127138D02*
X566870Y127488D01*
G01X524645Y170861D02*
Y173104D01*
G01X526245Y171335D02*
Y173104D01*
G01X525581Y169419D02*
X524645Y170861D01*
G01X559833Y119597D02*
X526245Y171335D01*
G01X558676Y118440D02*
X527536Y166407D01*
G01X559833Y119597D02*
X526245Y171335D01*
G01D02*
Y173104D01*
G01X524645Y170861D02*
Y173104D01*
G01X559833Y119597D02*
X526245Y171335D01*
G01X525581Y169419D02*
X524645Y170861D01*
G01X558676Y118440D02*
X527536Y166407D01*
G01X514547Y171471D02*
Y173135D01*
G01X516147Y171945D02*
Y173189D01*
G01X522831Y158715D02*
X514547Y171471D01*
G01X523988Y159872D02*
X516147Y171945D01*
G01X529241Y154553D02*
X522831Y158715D01*
G01X530398Y155710D02*
X523988Y159872D01*
G01X530430Y152722D02*
X529241Y154553D01*
G01X556141Y116056D02*
X530398Y155710D01*
G01X543605Y132427D02*
X532411Y149669D01*
G01X556141Y116056D02*
X530398Y155710D01*
G01X554983Y114899D02*
X543605Y132427D01*
G01X556141Y116056D02*
X530398Y155710D01*
G01X516147Y171945D02*
Y173189D01*
G01X514547Y171471D02*
Y173135D01*
G01X523988Y159872D02*
X516147Y171945D01*
G01X522831Y158715D02*
X514547Y171471D01*
G01X530398Y155710D02*
X523988Y159872D01*
G01X529241Y154553D02*
X522831Y158715D01*
G01X556141Y116056D02*
X530398Y155710D01*
G01X530430Y152722D02*
X529241Y154553D01*
G01X543605Y132427D02*
X532411Y149669D01*
G01X554983Y114899D02*
X543605Y132427D01*
G01X566889Y175449D02*
X573872Y173964D01*
G01X566266Y173945D02*
X573872Y172328D01*
G01X555302Y182970D02*
X566889Y175449D01*
G01X554145Y181813D02*
X566266Y173945D01*
G01D02*
X573872Y172328D01*
G01X566889Y175449D02*
X573872Y173964D01*
G01X554145Y181813D02*
X566266Y173945D01*
G01X555302Y182970D02*
X566889Y175449D01*
G01X556605Y169157D02*
X527859Y213425D01*
G01X557762Y170314D02*
X529016Y214582D01*
G01X573422Y158235D02*
X556605Y169157D01*
G01X561353Y167982D02*
X557762Y170314D01*
G01X565597Y165226D02*
X564364Y166027D01*
G01X574044Y159739D02*
X568608Y163270D01*
G01X571450Y152719D02*
X583462Y150163D01*
G01X570827Y151215D02*
X583449Y148529D01*
G01X570134Y153573D02*
X571450Y152719D01*
G01X569877Y151831D02*
X570827Y151215D01*
G01X556046Y160817D02*
X569877Y151831D01*
G01X565891Y156330D02*
X567124Y155529D01*
G01X556046Y160817D02*
X569877Y151831D01*
G01X557203Y161974D02*
X562881Y158285D01*
G01X556046Y160817D02*
X569877Y151831D01*
G01X525731Y210438D02*
X557203Y161974D01*
G01X524573Y209282D02*
X556046Y160817D01*
G01X570827Y151215D02*
X583449Y148529D01*
G01X571450Y152719D02*
X583462Y150163D01*
G01X569877Y151831D02*
X570827Y151215D01*
G01X570134Y153573D02*
X571450Y152719D01*
G01X556046Y160817D02*
X569877Y151831D01*
G01X570134Y153573D02*
X571450Y152719D01*
G01X565891Y156330D02*
X567124Y155529D01*
G01X557203Y161974D02*
X562881Y158285D01*
G01X524573Y209282D02*
X556046Y160817D01*
G01X525731Y210438D02*
X557203Y161974D01*
G01X557098Y150241D02*
X574644Y138848D01*
G01X569789Y143909D02*
X571022Y143108D01*
G01X565545Y146665D02*
X566778Y145864D01*
G01X558255Y151398D02*
X562534Y148620D01*
G01X522035Y204231D02*
X557098Y150241D01*
G01X523192Y205388D02*
X558255Y151398D01*
G01X565645Y128281D02*
X521269Y196503D01*
G01X558387Y142377D02*
X522429Y197655D01*
G01X561283Y137924D02*
X560481Y139156D01*
G01X564042Y133682D02*
X563240Y134914D01*
G01X566801Y129440D02*
X565999Y130672D01*
G01X566870Y127488D02*
X565645Y128281D01*
G01X567493Y128992D02*
X566801Y129440D01*
G01X568510Y127138D02*
X566870Y127488D01*
G01X568513Y128774D02*
X567493Y128992D01*
G01X512653Y159576D02*
X511866Y160087D01*
G01X514081Y160558D02*
X513023Y161244D01*
G01X523316Y152653D02*
X515664Y157621D01*
G01X524473Y153810D02*
X514081Y160557D01*
G01X536031Y133068D02*
X523316Y152653D01*
G01X550273Y114070D02*
X524473Y153810D01*
G01X550273Y114070D02*
X524473Y153810D01*
G01X514081Y160558D02*
X513023Y161244D01*
G01X512653Y159576D02*
X511866Y160087D01*
G01X524473Y153810D02*
X514081Y160557D01*
G01X523316Y152653D02*
X515664Y157621D01*
G01X550273Y114070D02*
X524473Y153810D01*
G01X536031Y133068D02*
X523316Y152653D01*
G01X521663Y146354D02*
X533670Y127862D01*
G01X512994Y151983D02*
X521663Y146354D01*
G01X512994Y151983D02*
X521663Y146354D01*
G01D02*
X533670Y127862D01*
G01X549546Y237069D02*
G02X548815Y238836I1768J1766D01*
G01X551313Y236338D02*
G02X549546Y237069I-1J2499D01*
G01D02*
G02X548815Y238836I1768J1766D01*
G01X551313Y236338D02*
G02X549546Y237069I-1J2499D01*
G01X559880Y236338D02*
X551313D01*
G01X568353D02*
X564222D01*
G01X573838D02*
X571943D01*
G01X524411Y236752D02*
X520665D01*
G01X530601Y237075D02*
X524582Y238352D01*
G01X529978Y235571D02*
X524411Y236752D01*
G01X559765Y218115D02*
X530601Y237075D01*
G01X559141Y216611D02*
X529978Y235571D01*
G01X566524Y216678D02*
X559765Y218115D01*
G01X574988Y213243D02*
X559141Y216611D01*
G01X571473Y215626D02*
X570035Y215932D01*
G01X574988Y213243D02*
X559141Y216611D01*
G01X571576Y183949D02*
X573031Y184256D01*
G01X571574Y182313D02*
X573364Y182691D01*
G01X567537Y184808D02*
X571576Y183949D01*
G01X566914Y183304D02*
X571574Y182313D01*
G01X565285Y186271D02*
X567537Y184808D01*
G01X557365Y189503D02*
X566914Y183304D01*
G01X558522Y190660D02*
X565285Y186270D01*
G01X557365Y189503D02*
X566914Y183304D01*
G01X557722Y191893D02*
X558522Y190660D01*
G01X538622Y218373D02*
X557365Y189503D01*
G01X554967Y196137D02*
X555767Y194904D01*
G01X538622Y218373D02*
X557365Y189503D01*
G01X546863Y208620D02*
X553012Y199148D01*
G01X538622Y218373D02*
X557365Y189503D01*
G01X539780Y219530D02*
X546863Y208620D01*
G01X538622Y218373D02*
X557365Y189503D01*
G01X527084Y227794D02*
X539780Y219530D01*
G01X526460Y226290D02*
X538622Y218373D01*
G01X520979Y229090D02*
X527084Y227794D01*
G01X520810Y227490D02*
X526460Y226290D01*
G01X519094Y229090D02*
X520979D01*
G01X519094Y227490D02*
X520810D01*
G01X549546Y237069D02*
G02X548815Y238836I1768J1766D01*
G01X551313Y236338D02*
G02X549546Y237069I-1J2499D01*
G01X559880Y236338D02*
X551313D01*
G01X550450Y230098D02*
Y231407D01*
G01X552050Y230098D02*
Y231403D01*
G01X551181Y228331D02*
G02X550450Y230098I1768J1766D01*
G01X552313Y229463D02*
G02X552050Y230098I635J635D01*
G01X552948Y229200D02*
G02X552313Y229463I0J898D01*
G01X552948Y227600D02*
G02X551181Y228331I-1J2499D01*
G01X552313Y229463D02*
G02X552050Y230098I635J635D01*
G01X552948Y229200D02*
G02X552313Y229463I0J898D01*
G01X561515Y227600D02*
X552948D01*
G01X561515Y229200D02*
X552948D01*
G01X552050Y230098D02*
Y231403D01*
G01X550450Y230098D02*
Y231407D01*
G01X552313Y229463D02*
G02X552050Y230098I635J635D01*
G01X551181Y228331D02*
G02X550450Y230098I1768J1766D01*
G01X552948Y227600D02*
G02X551181Y228331I-1J2499D01*
G01X552948Y229200D02*
G02X552313Y229463I0J898D01*
G01X551181Y228331D02*
G02X550450Y230098I1768J1766D01*
G01X552948Y227600D02*
G02X551181Y228331I-1J2499D01*
G01X561515Y229200D02*
X552948D01*
G01X561515Y227600D02*
X552948D01*
G01X524545Y180441D02*
Y178888D01*
G01X526145Y180441D02*
Y178888D01*
G01X524140Y181418D02*
G02X524545Y180441I-976J-977D01*
G01X525272Y182549D02*
G02X526145Y180441I-2109J-2108D01*
G01X523163Y183423D02*
G02X525272Y182549I0J-2982D01*
G01X523163Y181823D02*
G02X524140Y181418I0J-1381D01*
G01X525272Y182549D02*
G02X526145Y180441I-2109J-2108D01*
G01X523163Y183423D02*
G02X525272Y182549I0J-2982D01*
G01X520989Y181823D02*
X523163D01*
G01X520989Y183423D02*
X523163D01*
G01X526145Y180441D02*
Y178888D01*
G01X524545Y180441D02*
Y178888D01*
G01X525272Y182549D02*
G02X526145Y180441I-2109J-2108D01*
G01X524140Y181418D02*
G02X524545Y180441I-976J-977D01*
G01X523163Y181823D02*
G02X524140Y181418I0J-1381D01*
G01X523163Y183423D02*
G02X525272Y182549I0J-2982D01*
G01X524140Y181418D02*
G02X524545Y180441I-976J-977D01*
G01X523163Y181823D02*
G02X524140Y181418I0J-1381D01*
G01X520989Y183423D02*
X523163D01*
G01X520989Y181823D02*
X523163D01*
G01X568353Y236338D02*
X564222D01*
G01X573838D02*
X571943D01*
G01X565857Y227600D02*
X580747D01*
G01X580916Y229200D02*
X565857D01*
G01X580916D02*
X565857D01*
G01Y227600D02*
X580747D01*
G01X529016Y214582D02*
X522017Y219127D01*
G01X527859Y213425D02*
X521145Y217785D01*
G01X519530Y207767D02*
X523192Y205388D01*
G01X518366Y206613D02*
X522035Y204231D01*
G01X518835Y208834D02*
X519530Y207767D01*
G01X517494Y207961D02*
X518366Y206613D01*
G01X513428Y204212D02*
G02X512611Y206184I1971J1972D01*
G01X512296Y203080D02*
G02X511011Y206085I3103J3104D01*
G01X515236Y202404D02*
X513428Y204212D01*
G01X514219Y201158D02*
X512296Y203081D01*
G01X522429Y197655D02*
X515236Y202404D01*
G01X521269Y196503D02*
X514219Y201158D01*
G01X524411Y236752D02*
X520665D01*
G01X529978Y235571D02*
X524411Y236752D01*
G01X530601Y237075D02*
X524582Y238352D01*
G01X559141Y216611D02*
X529978Y235571D01*
G01X559765Y218115D02*
X530601Y237075D01*
G01X574988Y213243D02*
X559141Y216611D01*
G01X566524Y216678D02*
X559765Y218115D01*
G01X571473Y215626D02*
X570035Y215932D01*
G01X525548Y233027D02*
X518969D01*
G01X525379Y231427D02*
X518969D01*
G01X529196Y232248D02*
X525548Y233027D01*
G01X528568Y230746D02*
X525379Y231427D01*
G01X543501Y222848D02*
X529196Y232248D01*
G01X542342Y221695D02*
X528568Y230746D01*
G01X545067Y220437D02*
X543501Y222848D01*
G01X552720Y205716D02*
X542342Y221695D01*
G01X547823Y216194D02*
X547022Y217427D01*
G01X552720Y205716D02*
X542342Y221695D01*
G01X553877Y206874D02*
X549778Y213184D01*
G01X552720Y205716D02*
X542342Y221695D01*
G01X560046Y202871D02*
X553877Y206874D01*
G01X556091Y203530D02*
X552720Y205716D01*
G01X559423Y201367D02*
X556091Y203530D01*
G01X575532Y199577D02*
X560046Y202871D01*
G01X575532Y197941D02*
X559423Y201367D01*
G01X525379Y231427D02*
X518969D01*
G01X525548Y233027D02*
X518969D01*
G01X528568Y230746D02*
X525379Y231427D01*
G01X529196Y232248D02*
X525548Y233027D01*
G01X542342Y221695D02*
X528568Y230746D01*
G01X543501Y222848D02*
X529196Y232248D01*
G01X552720Y205716D02*
X542342Y221695D01*
G01X545067Y220437D02*
X543501Y222848D01*
G01X547823Y216194D02*
X547022Y217427D01*
G01X553877Y206874D02*
X549778Y213184D01*
G01X556091Y203530D02*
X552720Y205716D01*
G01X560046Y202871D02*
X553877Y206874D01*
G01X559423Y201367D02*
X556091Y203530D01*
G01X560046Y202871D02*
X553877Y206874D01*
G01X575532Y197941D02*
X559423Y201367D01*
G01X575532Y199577D02*
X560046Y202871D01*
G01X571574Y182313D02*
X573364Y182691D01*
G01X571576Y183949D02*
X573031Y184256D01*
G01X566914Y183304D02*
X571574Y182313D01*
G01X567537Y184808D02*
X571576Y183949D01*
G01X557365Y189503D02*
X566914Y183304D01*
G01X565285Y186271D02*
X567537Y184808D01*
G01X558522Y190660D02*
X565285Y186270D01*
G01X538622Y218373D02*
X557365Y189503D01*
G01X557722Y191893D02*
X558522Y190660D01*
G01X554967Y196137D02*
X555767Y194904D01*
G01X546863Y208620D02*
X553012Y199148D01*
G01X539780Y219530D02*
X546863Y208620D01*
G01X526460Y226290D02*
X538622Y218373D01*
G01X527084Y227794D02*
X539780Y219530D01*
G01X520810Y227490D02*
X526460Y226290D01*
G01X520979Y229090D02*
X527084Y227794D01*
G01X519094Y227490D02*
X520810D01*
G01X519094Y229090D02*
X520979D01*
G01X543613Y200973D02*
X555302Y182970D01*
G01X530841Y217703D02*
X554145Y181813D01*
G01X540857Y205217D02*
X541658Y203984D01*
G01X530841Y217703D02*
X554145Y181813D01*
G01X531998Y218860D02*
X538902Y208228D01*
G01X530841Y217703D02*
X554145Y181813D01*
G01X522695Y224903D02*
X531998Y218860D01*
G01X522220Y223303D02*
X530841Y217703D01*
G01X518561Y224903D02*
X522695D01*
G01X518561Y223303D02*
X522220D01*
G01X530841Y217703D02*
X554145Y181813D01*
G01X543613Y200973D02*
X555302Y182970D01*
G01X540857Y205217D02*
X541658Y203984D01*
G01X531998Y218860D02*
X538902Y208228D01*
G01X522220Y223303D02*
X530841Y217703D01*
G01X522695Y224903D02*
X531998Y218860D01*
G01X518561Y223303D02*
X522220D01*
G01X518561Y224903D02*
X522695D01*
G01X527859Y213425D02*
X521145Y217785D01*
G01X529016Y214582D02*
X522017Y219127D01*
G01X519873Y214255D02*
X525731Y210438D01*
G01X519000Y212914D02*
X524573Y209282D01*
G01X519000Y212914D02*
X524573Y209282D01*
G01X519873Y214255D02*
X525731Y210438D01*
G01X518366Y206613D02*
X522035Y204231D01*
G01X519530Y207767D02*
X523192Y205388D01*
G01X517494Y207961D02*
X518366Y206613D01*
G01X518835Y208834D02*
X519530Y207767D01*
G01X512296Y203080D02*
G02X511011Y206085I3103J3104D01*
G01X513428Y204212D02*
G02X512611Y206184I1971J1972D01*
G01X514219Y201158D02*
X512296Y203081D01*
G01X515236Y202404D02*
X513428Y204212D01*
G01X521269Y196503D02*
X514219Y201158D01*
G01X522429Y197655D02*
X515236Y202404D01*
G01X514102Y181563D02*
G03X513336Y181881I-767J-766D01*
G01X515234Y182695D02*
G03X513336Y183481I-1898J-1899D01*
G01X516020Y180797D02*
G03X515234Y182695I-2685J0D01*
G01X514420Y180797D02*
G03X514102Y181563I-1084J-1D01*
G01X515234Y182695D02*
G03X513336Y183481I-1898J-1899D01*
G01X516020Y180797D02*
G03X515234Y182695I-2685J0D01*
G01X514420Y178946D02*
Y180797D01*
G01X516020Y178946D02*
Y180797D01*
G01X515234Y182695D02*
G03X513336Y183481I-1898J-1899D01*
G01X514102Y181563D02*
G03X513336Y181881I-767J-766D01*
G01X514420Y180797D02*
G03X514102Y181563I-1084J-1D01*
G01X516020Y180797D02*
G03X515234Y182695I-2685J0D01*
G01X514102Y181563D02*
G03X513336Y181881I-767J-766D01*
G01X514420Y180797D02*
G03X514102Y181563I-1084J-1D01*
G01X516020Y178946D02*
Y180797D01*
G01X514420Y178946D02*
Y180797D01*
G01X521491Y294312D02*
X518605D01*
G01X520828Y295912D02*
X518605D01*
G01X522751Y295572D02*
X521491Y294312D01*
G01X531123Y306207D02*
X520828Y295912D01*
G01X531786Y304607D02*
X525290Y298111D01*
G01X531123Y306207D02*
X520828Y295912D01*
G01X548243Y299478D02*
Y300787D01*
G01X546643Y299478D02*
Y300783D01*
G01X547512Y297711D02*
G03X548243Y299478I-1768J1766D01*
G01X546380Y298843D02*
G03X546643Y299478I-635J635D01*
G01X545745Y298580D02*
G03X546380Y298843I0J898D01*
G01X545745Y296980D02*
G03X547512Y297711I1J2499D01*
G01X546380Y298843D02*
G03X546643Y299478I-635J635D01*
G01X545745Y298580D02*
G03X546380Y298843I0J898D01*
G01X537813Y296980D02*
X545745D01*
G01X537813Y298580D02*
X545745D01*
G01X546643Y299478D02*
Y300783D01*
G01X548243Y299478D02*
Y300787D01*
G01X546380Y298843D02*
G03X546643Y299478I-635J635D01*
G01X547512Y297711D02*
G03X548243Y299478I-1768J1766D01*
G01X545745Y296980D02*
G03X547512Y297711I1J2499D01*
G01X545745Y298580D02*
G03X546380Y298843I0J898D01*
G01X547512Y297711D02*
G03X548243Y299478I-1768J1766D01*
G01X545745Y296980D02*
G03X547512Y297711I1J2499D01*
G01X537813Y298580D02*
X545745D01*
G01X537813Y296980D02*
X545745D01*
G01X547667Y253994D02*
Y255303D01*
G01X549267Y253994D02*
Y255299D01*
G01X548398Y252227D02*
G02X547667Y253994I1768J1766D01*
G01X549530Y253359D02*
G02X549267Y253994I635J635D01*
G01X550165Y253096D02*
G02X549530Y253359I0J898D01*
G01X550165Y251496D02*
G02X548398Y252227I-1J2499D01*
G01X549530Y253359D02*
G02X549267Y253994I635J635D01*
G01X550165Y253096D02*
G02X549530Y253359I0J898D01*
G01X559756Y251496D02*
X550165D01*
G01X559755Y253096D02*
X550165D01*
G01X549267Y253994D02*
Y255299D01*
G01X547667Y253994D02*
Y255303D01*
G01X549530Y253359D02*
G02X549267Y253994I635J635D01*
G01X548398Y252227D02*
G02X547667Y253994I1768J1766D01*
G01X550165Y251496D02*
G02X548398Y252227I-1J2499D01*
G01X550165Y253096D02*
G02X549530Y253359I0J898D01*
G01X548398Y252227D02*
G02X547667Y253994I1768J1766D01*
G01X550165Y251496D02*
G02X548398Y252227I-1J2499D01*
G01X559755Y253096D02*
X550165D01*
G01X559756Y251496D02*
X550165D01*
G01X547925Y246407D02*
Y247716D01*
G01X549525Y246407D02*
Y247712D01*
G01X548656Y244640D02*
G02X547925Y246407I1768J1766D01*
G01X549788Y245772D02*
G02X549525Y246407I635J635D01*
G01X550423Y245509D02*
G02X549788Y245772I0J898D01*
G01X550423Y243909D02*
G02X548656Y244640I-1J2499D01*
G01X549788Y245772D02*
G02X549525Y246407I635J635D01*
G01X550423Y245509D02*
G02X549788Y245772I0J898D01*
G01X558990Y243909D02*
X550423D01*
G01X558990Y245509D02*
X550423D01*
G01X549525Y246407D02*
Y247712D01*
G01X547925Y246407D02*
Y247716D01*
G01X549788Y245772D02*
G02X549525Y246407I635J635D01*
G01X548656Y244640D02*
G02X547925Y246407I1768J1766D01*
G01X550423Y243909D02*
G02X548656Y244640I-1J2499D01*
G01X550423Y245509D02*
G02X549788Y245772I0J898D01*
G01X548656Y244640D02*
G02X547925Y246407I1768J1766D01*
G01X550423Y243909D02*
G02X548656Y244640I-1J2499D01*
G01X558990Y245509D02*
X550423D01*
G01X558990Y243909D02*
X550423D01*
G01X550415Y238836D02*
Y240141D01*
G01X548815Y238836D02*
Y240145D01*
G01X550678Y238201D02*
G02X550415Y238836I635J635D01*
G01X551313Y237938D02*
G02X550678Y238201I0J898D01*
G01X559880Y237938D02*
X551313D01*
G01X568167Y253047D02*
X585467Y249368D01*
G01X572642Y250459D02*
X574080Y250153D01*
G01X568167Y253047D02*
X585467Y249368D01*
G01X567693Y251512D02*
X569131Y251206D01*
G01X568167Y253047D02*
X585467Y249368D01*
G01X563585Y251512D02*
X567693D01*
G01X563553Y253112D02*
X568102D01*
G01X568167Y253047D02*
X585467Y249368D01*
G01X572642Y250459D02*
X574080Y250153D01*
G01X567693Y251512D02*
X569131Y251206D01*
G01X563553Y253112D02*
X568102D01*
G01X563585Y251512D02*
X567693D01*
G01X564979Y243909D02*
X563332D01*
G01X572150Y245509D02*
X563332D01*
G01X571946Y243909D02*
X568569D01*
G01X572150Y245509D02*
X563332D01*
G01X586534Y240137D02*
X571946Y243909D01*
G01X587187Y241621D02*
X572150Y245509D01*
G01D02*
X563332D01*
G01X564979Y243909D02*
X563332D01*
G01X571946D02*
X568569D01*
G01X587187Y241621D02*
X572150Y245509D01*
G01X586534Y240137D02*
X571946Y243909D01*
G01X574032Y237938D02*
X564222D01*
G01X524582Y238352D02*
X520665D01*
G01X548815Y238836D02*
Y240145D01*
G01X550415Y238836D02*
Y240141D01*
G01X550678Y238201D02*
G02X550415Y238836I635J635D01*
G01X551313Y237938D02*
G02X550678Y238201I0J898D01*
G01D02*
G02X550415Y238836I635J635D01*
G01X551313Y237938D02*
G02X550678Y238201I0J898D01*
G01X559880Y237938D02*
X551313D01*
G01X574032D02*
X564222D01*
G01X574032D02*
X564222D01*
G01X520828Y295912D02*
X518605D01*
G01X521491Y294312D02*
X518605D01*
G01X531123Y306207D02*
X520828Y295912D01*
G01X522751Y295572D02*
X521491Y294312D01*
G01X531786Y304607D02*
X525290Y298111D01*
G01X531803Y297097D02*
X533874D01*
G01X531140Y298697D02*
X534047D01*
G01X528880Y294174D02*
X531803Y297097D01*
G01X524492Y292049D02*
X531140Y298697D01*
G01X525155Y290449D02*
X526341Y291635D01*
G01X524492Y292049D02*
X531140Y298697D01*
G01X519204Y290449D02*
X525155D01*
G01X519204Y292049D02*
X524492D01*
G01X531140Y298697D02*
X534047D01*
G01X531803Y297097D02*
X533874D01*
G01X524492Y292049D02*
X531140Y298697D01*
G01X528880Y294174D02*
X531803Y297097D01*
G01X525155Y290449D02*
X526341Y291635D01*
G01X519204Y292049D02*
X524492D01*
G01X519204Y290449D02*
X525155D01*
G01X519241Y298837D02*
X520757Y300353D01*
G01X516677Y298837D02*
X519241D01*
G01D02*
X520757Y300353D01*
G01X516677Y298837D02*
X519241D01*
G01X524582Y238352D02*
X520665D01*
G01X516862Y302348D02*
X515215D01*
G01X516199Y303948D02*
X515215D01*
G01X523375Y308861D02*
X516862Y302348D01*
G01X521775Y309524D02*
X516199Y303948D01*
G01X523375Y311370D02*
Y308861D01*
G01X521775Y312033D02*
Y309524D01*
G01X524414Y312409D02*
X523375Y311370D01*
G01X528962Y319220D02*
X521775Y312033D01*
G01X529625Y317620D02*
X526953Y314948D01*
G01X528962Y319220D02*
X521775Y312033D01*
G01X533860Y317620D02*
X529625D01*
G01X534052Y319220D02*
X528962D01*
G01X545839Y304537D02*
X538153D01*
G01X538021Y306137D02*
X545839D01*
G01X548271Y306969D02*
G02X545839Y304537I-2432J0D01*
G01Y306137D02*
G03X546671Y306969I0J832D01*
G01X548271Y308278D02*
Y306969D01*
G01X546671D02*
Y308274D01*
G01Y306969D02*
Y308274D01*
G01X548271Y308278D02*
Y306969D01*
G01X545839Y306137D02*
G03X546671Y306969I0J832D01*
G01X548271D02*
G02X545839Y304537I-2432J0D01*
G01X538021Y306137D02*
X545839D01*
G01Y304537D02*
X538153D01*
G01X549677Y322247D02*
Y323556D01*
G01X548077Y322247D02*
Y323552D01*
G01X548947Y320481D02*
G03X549677Y322247I-1769J1765D01*
G01X547814Y321612D02*
G03X548077Y322247I-635J635D01*
G01X547179Y321349D02*
G03X547814Y321612I0J898D01*
G01X547179Y319749D02*
G03X548946Y320481I0J2499D01*
G01X547814Y321612D02*
G03X548077Y322247I-635J635D01*
G01X547179Y321349D02*
G03X547814Y321612I0J898D01*
G01X543065Y319749D02*
X547179D01*
G01X542402Y321349D02*
X547179D01*
G01X540919Y317603D02*
X543065Y319749D01*
G01X540256Y319203D02*
X542402Y321349D01*
G01X539189Y319203D02*
X540256D01*
G01X539395Y317603D02*
X540919D01*
G01X539189Y319203D02*
X540256D01*
G01X548077Y322247D02*
Y323552D01*
G01X549677Y322247D02*
Y323556D01*
G01X547814Y321612D02*
G03X548077Y322247I-635J635D01*
G01X548947Y320481D02*
G03X549677Y322247I-1769J1765D01*
G01X547179Y319749D02*
G03X548946Y320481I0J2499D01*
G01X547179Y321349D02*
G03X547814Y321612I0J898D01*
G01X548947Y320481D02*
G03X549677Y322247I-1769J1765D01*
G01X547179Y319749D02*
G03X548946Y320481I0J2499D01*
G01X542402Y321349D02*
X547179D01*
G01X543065Y319749D02*
X547179D01*
G01X540256Y319203D02*
X542402Y321349D01*
G01X540919Y317603D02*
X543065Y319749D01*
G01X539189Y319203D02*
X540256D01*
G01X540919Y317603D02*
X543065Y319749D01*
G01X539395Y317603D02*
X540919D01*
G01X546327Y311998D02*
X539220D01*
G01X546327Y313598D02*
X539220D01*
G01X547742Y312584D02*
G02X546327Y311998I-1415J1415D01*
G01X546610Y313716D02*
G02X546327Y313598I-284J283D01*
G01X546728Y313999D02*
G02X546610Y313716I-401J1D01*
G01X548328Y313999D02*
G02X547742Y312584I-2001J0D01*
G01X546610Y313716D02*
G02X546327Y313598I-284J283D01*
G01X546728Y313999D02*
G02X546610Y313716I-401J1D01*
G01X548328Y315245D02*
Y313999D01*
G01X546728Y315241D02*
Y313999D01*
G01X546327Y313598D02*
X539220D01*
G01X546327Y311998D02*
X539220D01*
G01X546610Y313716D02*
G02X546327Y313598I-284J283D01*
G01X547742Y312584D02*
G02X546327Y311998I-1415J1415D01*
G01X548328Y313999D02*
G02X547742Y312584I-2001J0D01*
G01X546728Y313999D02*
G02X546610Y313716I-401J1D01*
G01X547742Y312584D02*
G02X546327Y311998I-1415J1415D01*
G01X548328Y313999D02*
G02X547742Y312584I-2001J0D01*
G01X546728Y315241D02*
Y313999D01*
G01X548328Y315245D02*
Y313999D01*
G01X533655Y304607D02*
X531786D01*
G01X533753Y306207D02*
X531123D01*
G01X516199Y303948D02*
X515215D01*
G01X516862Y302348D02*
X515215D01*
G01X521775Y309524D02*
X516199Y303948D01*
G01X523375Y308861D02*
X516862Y302348D01*
G01X521775Y312033D02*
Y309524D01*
G01X523375Y311370D02*
Y308861D01*
G01X528962Y319220D02*
X521775Y312033D01*
G01X524414Y312409D02*
X523375Y311370D01*
G01X529625Y317620D02*
X526953Y314948D01*
G01X534052Y319220D02*
X528962D01*
G01X533860Y317620D02*
X529625D01*
G01X533753Y306207D02*
X531123D01*
G01X533655Y304607D02*
X531786D01*
G01X532479Y312075D02*
X533831D01*
G01X531816Y313675D02*
X533937D01*
G01X523295Y302891D02*
X532479Y312075D01*
G01X518578Y300437D02*
X531816Y313675D01*
G01X518578Y300437D02*
X531816Y313675D01*
G01X516677Y300437D02*
X518578D01*
G01X531816Y313675D02*
X533937D01*
G01X532479Y312075D02*
X533831D01*
G01X518578Y300437D02*
X531816Y313675D01*
G01X523295Y302891D02*
X532479Y312075D01*
G01X516677Y300437D02*
X518578D01*
G01X579577Y105281D02*
X577304Y106342D01*
G01X582427Y105717D02*
X578082Y107745D01*
G01X581915Y104189D02*
X579577Y105281D01*
G01X582427Y105717D02*
X578082Y107745D01*
G01X596628Y101060D02*
X581915Y104189D01*
G01X596628Y102696D02*
X582427Y105717D01*
G01X601112Y102015D02*
X596628Y101060D01*
G01X600489Y103519D02*
X596628Y102696D01*
G01X609361Y107368D02*
X601112Y102015D01*
G01X608204Y108526D02*
X600489Y103519D01*
G01X619873Y123551D02*
X609361Y107368D01*
G01X618715Y124707D02*
X608204Y108526D01*
G01X582427Y105717D02*
X578082Y107745D01*
G01X579577Y105281D02*
X577304Y106342D01*
G01X581915Y104189D02*
X579577Y105281D01*
G01X596628Y102696D02*
X582427Y105717D01*
G01X596628Y101060D02*
X581915Y104189D01*
G01X600489Y103519D02*
X596628Y102696D01*
G01X601112Y102015D02*
X596628Y101060D01*
G01X608204Y108526D02*
X600489Y103519D01*
G01X609361Y107368D02*
X601112Y102015D01*
G01X618715Y124707D02*
X608204Y108526D01*
G01X619873Y123551D02*
X609361Y107368D01*
G01X596765Y96109D02*
X577659Y100169D01*
G01X596765Y97745D02*
X578282Y101673D01*
G01X602883Y97411D02*
X596765Y96109D01*
G01X602260Y98915D02*
X596765Y97745D01*
G01X614325Y104840D02*
X602883Y97411D01*
G01X613168Y105997D02*
X602260Y98915D01*
G01X623052Y118278D02*
X614325Y104840D01*
G01X621895Y119435D02*
X613168Y105997D01*
G01X596765Y97745D02*
X578282Y101673D01*
G01X596765Y96109D02*
X577659Y100169D01*
G01X602260Y98915D02*
X596765Y97745D01*
G01X602883Y97411D02*
X596765Y96109D01*
G01X613168Y105997D02*
X602260Y98915D01*
G01X614325Y104840D02*
X602883Y97411D01*
G01X621895Y119435D02*
X613168Y105997D01*
G01X623052Y118278D02*
X614325Y104840D01*
G01X596883Y91129D02*
X575744Y95625D01*
G01X596883Y92765D02*
X576367Y97129D01*
G01X604543Y92756D02*
X596883Y91129D01*
G01X603920Y94260D02*
X596883Y92765D01*
G01X621143Y103543D02*
X604543Y92756D01*
G01X619985Y104700D02*
X603920Y94260D01*
G01X629151Y115878D02*
X621143Y103543D01*
G01X627994Y117035D02*
X619985Y104700D01*
G01X596883Y92765D02*
X576367Y97129D01*
G01X596883Y91129D02*
X575744Y95625D01*
G01X603920Y94260D02*
X596883Y92765D01*
G01X604543Y92756D02*
X596883Y91129D01*
G01X619985Y104700D02*
X603920Y94260D01*
G01X621143Y103543D02*
X604543Y92756D01*
G01X627994Y117035D02*
X619985Y104700D01*
G01X629151Y115878D02*
X621143Y103543D01*
G01X633419Y111687D02*
X643307Y118109D01*
G01X642849Y119721D02*
X632262Y112844D01*
G01X626734Y101393D02*
X633419Y111687D01*
G01X632262Y112844D02*
X625577Y102550D01*
G01X623726Y99439D02*
X626734Y101393D01*
G01X625577Y102550D02*
X605901Y89770D01*
G01X606524Y88266D02*
X620715Y97483D01*
G01X625577Y102550D02*
X605901Y89770D01*
G01X596820Y86206D02*
X606524Y88266D01*
G01X605901Y89770D02*
X596820Y87842D01*
G01X573797Y91099D02*
X596820Y86206D01*
G01Y87842D02*
X574420Y92603D01*
G01X596820Y87842D02*
X574420Y92603D01*
G01X573797Y91099D02*
X596820Y86206D01*
G01X605901Y89770D02*
X596820Y87842D01*
G01Y86206D02*
X606524Y88266D01*
G01X625577Y102550D02*
X605901Y89770D01*
G01X623726Y99439D02*
X626734Y101393D01*
G01X606524Y88266D02*
X620715Y97483D01*
G01X632262Y112844D02*
X625577Y102550D01*
G01X626734Y101393D02*
X633419Y111687D01*
G01X642849Y119721D02*
X632262Y112844D01*
G01X633419Y111687D02*
X643307Y118109D01*
G01X587588Y175039D02*
X588812Y175291D01*
G01X587588Y175039D02*
X588812Y175291D01*
G01X584947Y161233D02*
X583437Y160913D01*
G01X585179Y159645D02*
X583813Y159356D01*
G01X585346Y159681D02*
X585179Y159645D01*
G01D02*
X583813Y159356D01*
G01X584947Y161233D02*
X583437Y160913D01*
G01X585346Y159681D02*
X585179Y159645D01*
G01X584947Y161233D02*
X583437Y160913D01*
G01X592758Y152085D02*
X594407Y152434D01*
G01X594500Y150817D02*
X593134Y150528D01*
G01X594667Y150853D02*
X594500Y150817D01*
G01D02*
X593134Y150528D01*
G01X592758Y152085D02*
X594407Y152434D01*
G01X594667Y150853D02*
X594500Y150817D01*
G01X592758Y152085D02*
X594407Y152434D01*
G01X586345Y140943D02*
X586997Y141077D01*
G01X587176Y139480D02*
X586682Y139378D01*
G01X586344Y140943D02*
X586345D01*
G01X586682Y139378D02*
X585633Y139142D01*
G01X586332Y140940D02*
X586344Y140943D01*
G01X586682Y139378D02*
X585633Y139142D01*
G01X585544Y140764D02*
X586332Y140940D01*
G01X586682Y139378D02*
X585633Y139142D01*
G01X586682Y139378D02*
X585633Y139142D01*
G01X586344Y140943D02*
X586345D01*
G01X586332Y140940D02*
X586344Y140943D01*
G01X585544Y140764D02*
X586332Y140940D01*
G01X587176Y139480D02*
X586682Y139378D01*
G01X586345Y140943D02*
X586997Y141077D01*
G01X574360Y129943D02*
X575795Y130238D01*
G01X574682Y128375D02*
X575974Y128641D01*
G01X574666Y128372D02*
X574682Y128375D01*
G01X587588Y175039D02*
X588812Y175291D01*
G01X587588Y175039D02*
X588812Y175291D01*
G01X584947Y161233D02*
X583437Y160913D01*
G01X585179Y159645D02*
X583813Y159356D01*
G01X585346Y159681D02*
X585179Y159645D01*
G01D02*
X583813Y159356D01*
G01X584947Y161233D02*
X583437Y160913D01*
G01X585346Y159681D02*
X585179Y159645D01*
G01X584947Y161233D02*
X583437Y160913D01*
G01X592758Y152085D02*
X594407Y152434D01*
G01X594500Y150817D02*
X593134Y150528D01*
G01X594667Y150853D02*
X594500Y150817D01*
G01D02*
X593134Y150528D01*
G01X592758Y152085D02*
X594407Y152434D01*
G01X594667Y150853D02*
X594500Y150817D01*
G01X592758Y152085D02*
X594407Y152434D01*
G01X586345Y140943D02*
X586997Y141077D01*
G01X587176Y139480D02*
X586682Y139378D01*
G01X586344Y140943D02*
X586345D01*
G01X586682Y139378D02*
X585633Y139142D01*
G01X586332Y140940D02*
X586344Y140943D01*
G01X586682Y139378D02*
X585633Y139142D01*
G01X585544Y140764D02*
X586332Y140940D01*
G01X586682Y139378D02*
X585633Y139142D01*
G01X586682Y139378D02*
X585633Y139142D01*
G01X586344Y140943D02*
X586345D01*
G01X586332Y140940D02*
X586344Y140943D01*
G01X585544Y140764D02*
X586332Y140940D01*
G01X587176Y139480D02*
X586682Y139378D01*
G01X586345Y140943D02*
X586997Y141077D01*
G01X574682Y128375D02*
X575974Y128641D01*
G01X574360Y129943D02*
X575795Y130238D01*
G01X574666Y128372D02*
X574682Y128375D01*
G01X574360Y129943D02*
X575795Y130238D01*
G01X627195Y153450D02*
X636456Y151481D01*
G01X617977Y157045D02*
X637079Y152985D01*
G01X617354Y155541D02*
X627195Y153450D01*
G01X617977Y157045D02*
X637079Y152985D01*
G01X614552Y157359D02*
X617354Y155541D01*
G01X617410Y157413D02*
X617977Y157045D01*
G01X617409Y157413D02*
X617410D01*
G01X615709Y158517D02*
X617409Y157413D01*
G01X612385Y160694D02*
X614552Y157359D01*
G01X613889Y161317D02*
X615709Y158517D01*
G01X608865Y177243D02*
X612385Y160694D01*
G01X610501Y177243D02*
X613889Y161317D01*
G01X617977Y157045D02*
X637079Y152985D01*
G01X627195Y153450D02*
X636456Y151481D01*
G01X617354Y155541D02*
X627195Y153450D01*
G01X617410Y157413D02*
X617977Y157045D01*
G01X614552Y157359D02*
X617354Y155541D01*
G01X617409Y157413D02*
X617410D01*
G01X614552Y157359D02*
X617354Y155541D01*
G01X615709Y158517D02*
X617409Y157413D01*
G01X614552Y157359D02*
X617354Y155541D01*
G01X613889Y161317D02*
X615709Y158517D01*
G01X612385Y160694D02*
X614552Y157359D01*
G01X610501Y177243D02*
X613889Y161317D01*
G01X608865Y177243D02*
X612385Y160694D01*
G01X607876Y158838D02*
X603944Y177340D01*
G01X609380Y159461D02*
X605580Y177340D01*
G01X611596Y153111D02*
X607876Y158838D01*
G01X612753Y154268D02*
X609380Y159461D01*
G01X615499Y150576D02*
X611596Y153111D01*
G01X614439Y153173D02*
X612753Y154268D01*
G01X616122Y152080D02*
X614439Y153174D01*
G01X616929Y150272D02*
X615499Y150576D01*
G01X635000Y148056D02*
X616122Y152080D01*
G01X621885Y149215D02*
X620447Y149521D01*
G01X635000Y148056D02*
X616122Y152080D01*
G01X626834Y148160D02*
X625396Y148466D01*
G01X635000Y148056D02*
X616122Y152080D01*
G01X634831Y146456D02*
X630345Y147412D01*
G01X635000Y148056D02*
X616122Y152080D01*
G01X643307Y146456D02*
X634831D01*
G01X644027Y148056D02*
X635000D01*
G01X609380Y159461D02*
X605580Y177340D01*
G01X607876Y158838D02*
X603944Y177340D01*
G01X612753Y154268D02*
X609380Y159461D01*
G01X611596Y153111D02*
X607876Y158838D01*
G01X614439Y153173D02*
X612753Y154268D01*
G01X615499Y150576D02*
X611596Y153111D01*
G01X616122Y152080D02*
X614439Y153174D01*
G01X615499Y150576D02*
X611596Y153111D01*
G01X635000Y148056D02*
X616122Y152080D01*
G01X616929Y150272D02*
X615499Y150576D01*
G01X621885Y149215D02*
X620447Y149521D01*
G01X626834Y148160D02*
X625396Y148466D01*
G01X634831Y146456D02*
X630345Y147412D01*
G01X644027Y148056D02*
X635000D01*
G01X643307Y146456D02*
X634831D01*
G01X604800Y157715D02*
X600597Y177458D01*
G01X603296Y157092D02*
X598961Y177458D01*
G01X609512Y150460D02*
X604800Y157715D01*
G01X608355Y149303D02*
X603296Y157092D01*
G01X616410Y145980D02*
X609512Y150460D01*
G01X615787Y144476D02*
X608355Y149303D01*
G01X633751Y142292D02*
X616410Y145980D01*
G01X633128Y140788D02*
X615787Y144476D01*
G01X636356Y140600D02*
X633751Y142292D01*
G01X635882Y139000D02*
X633128Y140788D01*
G01X603296Y157092D02*
X598961Y177458D01*
G01X604800Y157715D02*
X600597Y177458D01*
G01X608355Y149303D02*
X603296Y157092D01*
G01X609512Y150460D02*
X604800Y157715D01*
G01X615787Y144476D02*
X608355Y149303D01*
G01X616410Y145980D02*
X609512Y150460D01*
G01X633128Y140788D02*
X615787Y144476D01*
G01X633751Y142292D02*
X616410Y145980D01*
G01X635882Y139000D02*
X633128Y140788D01*
G01X636356Y140600D02*
X633751Y142292D01*
G01X632854Y135900D02*
X641529D01*
G01X640866Y137500D02*
X633023D01*
G01X614004Y139906D02*
X632854Y135900D01*
G01X633023Y137500D02*
X614627Y141410D01*
G01X604911Y145810D02*
X614004Y139906D01*
G01X614627Y141410D02*
X606068Y146967D01*
G01X598723Y155337D02*
X604911Y145810D01*
G01X606068Y146967D02*
X600227Y155960D01*
G01X597968Y158889D02*
X598723Y155337D01*
G01X600227Y155960D02*
X595624Y177616D01*
G01X596916Y163839D02*
X597222Y162401D01*
G01X600227Y155960D02*
X595624Y177616D01*
G01X593988D02*
X596170Y167350D01*
G01X600227Y155960D02*
X595624Y177616D01*
G01X600227Y155960D02*
X595624Y177616D01*
G01X597968Y158889D02*
X598723Y155337D01*
G01X596916Y163839D02*
X597222Y162401D01*
G01X593988Y177616D02*
X596170Y167350D01*
G01X606068Y146967D02*
X600227Y155960D01*
G01X598723Y155337D02*
X604911Y145810D01*
G01X614627Y141410D02*
X606068Y146967D01*
G01X604911Y145810D02*
X614004Y139906D01*
G01X633023Y137500D02*
X614627Y141410D01*
G01X614004Y139906D02*
X632854Y135900D01*
G01X640866Y137500D02*
X633023D01*
G01X632854Y135900D02*
X641529D01*
G01X574360Y129943D02*
X575795Y130238D01*
G01X574682Y128375D02*
X575974Y128641D01*
G01X574666Y128372D02*
X574682Y128375D01*
G01X576545Y159209D02*
X574044Y159739D01*
G01X573713Y158173D02*
X573422Y158235D01*
G01X573714Y158173D02*
X573713D01*
G01X576537Y157574D02*
X573714Y158173D01*
G01X578004Y159504D02*
X576545Y159209D01*
G01X578742Y158020D02*
X576537Y157574D01*
G01X578661Y139632D02*
X580379Y139998D01*
G01X578662Y137996D02*
X580555Y138399D01*
G01X575268Y140352D02*
X578661Y139632D01*
G01X574937Y138786D02*
X578662Y137996D01*
G01X574936Y138786D02*
X574937D01*
G01X574644Y138848D02*
X574936Y138786D01*
G01X575266Y140352D02*
X575268D01*
G01X574937Y138786D02*
X578662Y137996D01*
G01X574033Y141153D02*
X575266Y140352D01*
G01X627047Y128212D02*
X619874Y123552D01*
G01X626425Y129716D02*
X618714Y124708D01*
G01X638842Y130708D02*
X627047Y128212D01*
G01X638674Y132308D02*
X626425Y129716D01*
G01D02*
X618714Y124708D01*
G01X627047Y128212D02*
X619874Y123552D01*
G01X638674Y132308D02*
X626425Y129716D01*
G01X638842Y130708D02*
X627047Y128212D01*
G01X635437Y126322D02*
X623052Y118278D01*
G01X634815Y127826D02*
X621895Y119435D01*
G01X641094Y129159D02*
X634815Y127826D01*
G01X641094Y129159D02*
X634815Y127826D01*
G01X641094Y129159D02*
X634815Y127826D01*
G01X641094Y129159D02*
X634815Y127826D01*
G01D02*
X621895Y119435D01*
G01X635437Y126322D02*
X623052Y118278D01*
G01X641094Y129159D02*
X634815Y127826D01*
G01X573872Y173964D02*
X582025Y175696D01*
G01X573872Y172328D02*
X582115Y174079D01*
G01X573872Y172328D02*
X582115Y174079D01*
G01X573872Y173964D02*
X582025Y175696D01*
G01X573713Y158173D02*
X573422Y158235D01*
G01X576545Y159209D02*
X574044Y159739D01*
G01X573714Y158173D02*
X573713D01*
G01X576545Y159209D02*
X574044Y159739D01*
G01X576537Y157574D02*
X573714Y158173D01*
G01X576545Y159209D02*
X574044Y159739D01*
G01X578742Y158020D02*
X576537Y157574D01*
G01X578004Y159504D02*
X576545Y159209D01*
G01X586688Y150794D02*
X587167Y150896D01*
G01X583449Y148529D02*
X587017Y149228D01*
G01X586687Y150794D02*
X586688D01*
G01X583449Y148529D02*
X587017Y149228D01*
G01X583462Y150163D02*
X586687Y150794D01*
G01X587017Y149228D02*
X587255Y149278D01*
G01X583449Y148529D02*
X587017Y149228D01*
G01D02*
X587255Y149278D01*
G01X583462Y150163D02*
X586687Y150794D01*
G01X583449Y148529D02*
X587017Y149228D01*
G01X586688Y150794D02*
X587167Y150896D01*
G01X586687Y150794D02*
X586688D01*
G01X583462Y150163D02*
X586687Y150794D01*
G01X578662Y137996D02*
X580555Y138399D01*
G01X578661Y139632D02*
X580379Y139998D01*
G01X574937Y138786D02*
X578662Y137996D01*
G01X575268Y140352D02*
X578661Y139632D01*
G01X575266Y140352D02*
X575268D01*
G01X574936Y138786D02*
X574937D01*
G01X575268Y140352D02*
X578661Y139632D01*
G01X574644Y138848D02*
X574936Y138786D01*
G01X575268Y140352D02*
X578661Y139632D01*
G01X575266Y140352D02*
X575268D01*
G01X574033Y141153D02*
X575266Y140352D01*
G01X633300Y118570D02*
X629151Y115878D01*
G01X636975Y122864D02*
X627994Y117035D01*
G01X637449Y121263D02*
X633300Y118570D01*
G01X636975Y122864D02*
X627994Y117035D01*
G01X636975Y122864D02*
X627994Y117035D01*
G01X633300Y118570D02*
X629151Y115878D01*
G01X637449Y121263D02*
X633300Y118570D01*
G01X588062Y216964D02*
X586438Y216630D01*
G01X588241Y215367D02*
X586617Y215033D01*
G01X588241Y215367D02*
X586617Y215033D01*
G01X588062Y216964D02*
X586438Y216630D01*
G01X582502Y201045D02*
X583937Y201340D01*
G01X582824Y199477D02*
X584116Y199743D01*
G01X582808Y199474D02*
X582824Y199477D01*
G01D02*
X584116Y199743D01*
G01X582502Y201045D02*
X583937Y201340D01*
G01X582808Y199474D02*
X582824Y199477D01*
G01X582502Y201045D02*
X583937Y201340D01*
G01X578377Y185421D02*
X579812Y185716D01*
G01X578699Y183853D02*
X578683Y183850D01*
G01X579991Y184119D02*
X578699Y183853D01*
G01D02*
X578683Y183850D01*
G01X578377Y185421D02*
X579812Y185716D01*
G01X579991Y184119D02*
X578699Y183853D01*
G01X578377Y185421D02*
X579812Y185716D01*
G01X587243Y176603D02*
X588633Y176888D01*
G01X587243Y176603D02*
X588633Y176888D01*
G01X588062Y216964D02*
X586438Y216630D01*
G01X588241Y215367D02*
X586617Y215033D01*
G01X588241Y215367D02*
X586617Y215033D01*
G01X588062Y216964D02*
X586438Y216630D01*
G01X582502Y201045D02*
X583937Y201340D01*
G01X582824Y199477D02*
X584116Y199743D01*
G01X582808Y199474D02*
X582824Y199477D01*
G01D02*
X584116Y199743D01*
G01X582502Y201045D02*
X583937Y201340D01*
G01X582808Y199474D02*
X582824Y199477D01*
G01X582502Y201045D02*
X583937Y201340D01*
G01X578377Y185421D02*
X579812Y185716D01*
G01X578699Y183853D02*
X578683Y183850D01*
G01X579991Y184119D02*
X578699Y183853D01*
G01D02*
X578683Y183850D01*
G01X578377Y185421D02*
X579812Y185716D01*
G01X579991Y184119D02*
X578699Y183853D01*
G01X578377Y185421D02*
X579812Y185716D01*
G01X587243Y176603D02*
X588633Y176888D01*
G01X587243Y176603D02*
X588633Y176888D01*
G01X614242Y202498D02*
X608865Y177243D01*
G01X615879Y202499D02*
X610501Y177243D01*
G01X612889Y208887D02*
X614242Y202498D01*
G01X615504Y204265D02*
X615879Y202499D01*
G01X611336Y223959D02*
X615503Y204269D01*
G01X611842Y213837D02*
X612147Y212399D01*
G01X611336Y223959D02*
X615503Y204269D01*
G01X609832Y223337D02*
X611099Y217349D01*
G01X611336Y223959D02*
X615503Y204269D01*
G01X600512Y237689D02*
X609832Y223337D01*
G01X601669Y238846D02*
X611336Y223959D01*
G01X615879Y202499D02*
X610501Y177243D01*
G01X614242Y202498D02*
X608865Y177243D01*
G01X615504Y204265D02*
X615879Y202499D01*
G01X612889Y208887D02*
X614242Y202498D01*
G01X611336Y223959D02*
X615503Y204269D01*
G01X612889Y208887D02*
X614242Y202498D01*
G01X611842Y213837D02*
X612147Y212399D01*
G01X609832Y223337D02*
X611099Y217349D01*
G01X601669Y238846D02*
X611336Y223959D01*
G01X600512Y237689D02*
X609832Y223337D01*
G01X597540Y232991D02*
X586534Y240137D01*
G01X598697Y234148D02*
X587187Y241621D01*
G01X603729Y223457D02*
X597540Y232991D01*
G01X605233Y224080D02*
X598697Y234148D01*
G01X608738Y199896D02*
X603729Y223457D01*
G01X610374Y199896D02*
X605233Y224080D01*
G01X604015Y177673D02*
X608738Y199896D01*
G01X605580Y177340D02*
X610374Y199896D01*
G01X603944Y177340D02*
X604014Y177673D01*
G01X605580Y177340D02*
X610374Y199896D01*
G01X598697Y234148D02*
X587187Y241621D01*
G01X597540Y232991D02*
X586534Y240137D01*
G01X605233Y224080D02*
X598697Y234148D01*
G01X603729Y223457D02*
X597540Y232991D01*
G01X610374Y199896D02*
X605233Y224080D01*
G01X608738Y199896D02*
X603729Y223457D01*
G01X605580Y177340D02*
X610374Y199896D01*
G01X604015Y177673D02*
X608738Y199896D01*
G01X603944Y177340D02*
X604014Y177673D01*
G01X580465Y236360D02*
X574032Y237938D01*
G01X580108Y234800D02*
X573838Y236338D01*
G01X587603Y234844D02*
X580465Y236360D01*
G01X586980Y233340D02*
X580108Y234800D01*
G01X596016Y229379D02*
X587603Y234844D01*
G01X594859Y228222D02*
X586980Y233340D01*
G01X600618Y222293D02*
X596016Y229379D01*
G01X599114Y221670D02*
X594859Y228222D01*
G01X605373Y199912D02*
X600618Y222293D01*
G01X600582Y214761D02*
X599114Y221670D01*
G01X601634Y209811D02*
X601328Y211249D01*
G01X602685Y204862D02*
X602380Y206299D01*
G01X603737Y199912D02*
X603431Y201350D01*
G01X600597Y177458D02*
X605373Y199912D01*
G01X598961Y177458D02*
X603737Y199912D01*
G01X576561Y214544D02*
X574984Y214880D01*
G01X576560Y212907D02*
X574988Y213243D01*
G01X581119Y215514D02*
X576561Y214544D01*
G01X581563Y213971D02*
X576560Y212907D01*
G01X580108Y234800D02*
X573838Y236338D01*
G01X580465Y236360D02*
X574032Y237938D01*
G01X586980Y233340D02*
X580108Y234800D01*
G01X587603Y234844D02*
X580465Y236360D01*
G01X594859Y228222D02*
X586980Y233340D01*
G01X596016Y229379D02*
X587603Y234844D01*
G01X599114Y221670D02*
X594859Y228222D01*
G01X600618Y222293D02*
X596016Y229379D01*
G01X600582Y214761D02*
X599114Y221670D01*
G01X605373Y199912D02*
X600618Y222293D01*
G01X601634Y209811D02*
X601328Y211249D01*
G01X605373Y199912D02*
X600618Y222293D01*
G01X602685Y204862D02*
X602380Y206299D01*
G01X605373Y199912D02*
X600618Y222293D01*
G01X603737Y199912D02*
X603431Y201350D01*
G01X605373Y199912D02*
X600618Y222293D01*
G01X598961Y177458D02*
X603737Y199912D01*
G01X600597Y177458D02*
X605373Y199912D01*
G01X595030Y182517D02*
X593988Y177616D01*
G01X595624D02*
X599825Y197364D01*
G01X596083Y187466D02*
X595777Y186028D01*
G01X595624Y177616D02*
X599825Y197364D01*
G01X598189D02*
X596830Y190977D01*
G01X595624Y177616D02*
X599825Y197364D01*
G01X593294Y220389D02*
X598189Y197364D01*
G01X599825D02*
X594798Y221012D01*
G01X591538Y223093D02*
X593294Y220389D01*
G01X594798Y221012D02*
X592695Y224250D01*
G01X586473Y226383D02*
X591538Y223093D01*
G01X592695Y224250D02*
X587095Y227887D01*
G01X583610Y226990D02*
X586473Y226383D01*
G01X587095Y227887D02*
X580916Y229200D01*
G01X580747Y227600D02*
X583610Y226991D01*
G01X587095Y227887D02*
X580916Y229200D01*
G01X587095Y227887D02*
X580916Y229200D01*
G01X583610Y226990D02*
X586473Y226383D01*
G01X580747Y227600D02*
X583610Y226991D01*
G01X592695Y224250D02*
X587095Y227887D01*
G01X586473Y226383D02*
X591538Y223093D01*
G01X594798Y221012D02*
X592695Y224250D01*
G01X591538Y223093D02*
X593294Y220389D01*
G01X599825Y197364D02*
X594798Y221012D01*
G01X593294Y220389D02*
X598189Y197364D01*
G01X595624Y177616D02*
X599825Y197364D01*
G01X595030Y182517D02*
X593988Y177616D01*
G01X596083Y187466D02*
X595777Y186028D01*
G01X598189Y197364D02*
X596830Y190977D01*
G01X576560Y212907D02*
X574988Y213243D01*
G01X576561Y214544D02*
X574984Y214880D01*
G01X581563Y213971D02*
X576560Y212907D01*
G01X581119Y215514D02*
X576561Y214544D01*
G01X577188Y199930D02*
X575532Y199577D01*
G01X577634Y198388D02*
X575532Y197941D01*
G01X577634Y198388D02*
X575532Y197941D01*
G01X577188Y199930D02*
X575532Y199577D01*
G01X600329Y237807D02*
X600512Y237689D01*
G01X585467Y249368D02*
X601669Y238846D01*
G01X592677Y242776D02*
X600329Y237807D01*
G01X585467Y249368D02*
X601669Y238846D01*
G01X584844Y247864D02*
X592677Y242776D01*
G01X585467Y249368D02*
X601669Y238846D01*
G01X577591Y249406D02*
X584844Y247864D01*
G01X585467Y249368D02*
X601669Y238846D01*
G01X600329Y237807D02*
X600512Y237689D01*
G01X592677Y242776D02*
X600329Y237807D01*
G01X584844Y247864D02*
X592677Y242776D01*
G01X577591Y249406D02*
X584844Y247864D01*
G01X639342Y149606D02*
X643307D01*
G01X639817Y151206D02*
X643596D01*
G01X636456Y151481D02*
X639342Y149606D01*
G01X637079Y152985D02*
X639817Y151206D01*
G01D02*
X643596D01*
G01X639342Y149606D02*
X643307D01*
G01X637079Y152985D02*
X639817Y151206D01*
G01X636456Y151481D02*
X639342Y149606D01*
G01X639840Y140600D02*
X636356D01*
G01X640503Y139000D02*
X635882D01*
G01X640997Y141757D02*
X639840Y140600D01*
G01X641660Y140157D02*
X640503Y139000D01*
G01X643717Y141757D02*
X640997D01*
G01X643307Y140157D02*
X641660D01*
G01X640503Y139000D02*
X635882D01*
G01X639840Y140600D02*
X636356D01*
G01X641660Y140157D02*
X640503Y139000D01*
G01X640997Y141757D02*
X639840Y140600D01*
G01X643307Y140157D02*
X641660D01*
G01X643717Y141757D02*
X640997D01*
G01X642637Y137008D02*
X643307D01*
G01Y138608D02*
X641974D01*
G01X641529Y135900D02*
X642637Y137008D01*
G01X641974Y138608D02*
X640866Y137500D01*
G01X641974Y138608D02*
X640866Y137500D01*
G01X641529Y135900D02*
X642637Y137008D01*
G01X643307Y138608D02*
X641974D01*
G01X642637Y137008D02*
X643307D01*
G01Y130708D02*
X638842D01*
G01X643599Y132308D02*
X638674D01*
G01X643599D02*
X638674D01*
G01X643307Y130708D02*
X638842D01*
G01X636528Y126553D02*
X635437Y126322D01*
G01X637621Y126785D02*
X636528Y126553D01*
G01X639806Y127249D02*
X637621Y126785D01*
G01X641263Y127559D02*
X639806Y127249D01*
G01X643307Y127559D02*
X641263D01*
G01X643560Y129159D02*
X641094D01*
G01X636528Y126553D02*
X635437Y126322D01*
G01X637621Y126785D02*
X636528Y126553D01*
G01X639806Y127249D02*
X637621Y126785D01*
G01X641263Y127559D02*
X639806Y127249D01*
G01X643560Y129159D02*
X641094D01*
G01X643307Y127559D02*
X641263D01*
G01X643303Y121264D02*
X637449D01*
G01X643638Y122864D02*
X636975D01*
G01X643638D02*
X636975D01*
G01X643303Y121264D02*
X637449D01*
G54D13*
G01X702183Y31277D02*
X672275Y61185D01*
G01X685923Y49270D02*
X684703Y50490D01*
G01X702691Y32502D02*
X687991Y47202D01*
G01X702183Y31277D02*
X672275Y61185D01*
G01X702183Y31277D02*
X672275Y61185D01*
G01X702183Y31277D02*
X672275Y61185D01*
G01X685923Y49270D02*
X684703Y50490D01*
G01X702183Y31277D02*
X672275Y61185D01*
G01X702691Y32502D02*
X687991Y47202D01*
G01X702183Y31277D02*
X672275Y61185D01*
G01X693863Y109271D02*
X701363Y101771D01*
G01X695088Y109779D02*
X701871Y102996D01*
G01X693863Y111648D02*
Y109271D01*
G01X695088Y113572D02*
Y109779D01*
G01D02*
X701871Y102996D01*
G01X693863Y109271D02*
X701363Y101771D01*
G01X695088Y113572D02*
Y109779D01*
G01X693863Y111648D02*
Y109271D01*
G01X690945Y106545D02*
Y111417D01*
G01X692170Y112268D02*
Y107053D01*
G01X697983Y99507D02*
X690945Y106545D01*
G01X692170Y107053D02*
X699208Y100015D01*
G01X692170Y107053D02*
X699208Y100015D01*
G01X697983Y99507D02*
X690945Y106545D01*
G01X692170Y112268D02*
Y107053D01*
G01X690945Y106545D02*
Y111417D01*
G01X684415Y106500D02*
Y111648D01*
G01X685640Y112460D02*
Y107008D01*
G01X689744Y101171D02*
X684415Y106500D01*
G01X685640Y107008D02*
X690969Y101679D01*
G01X689744Y94309D02*
Y101171D01*
G01X690969Y101679D02*
Y94309D01*
G01X691957Y92096D02*
G02X689744Y94309I0J2213D01*
G01X690969D02*
G03X691957Y93321I988J0D01*
G01X693227Y92096D02*
X691957D01*
G01Y93321D02*
X693228D01*
G01X691957D02*
X693228D01*
G01X693227Y92096D02*
X691957D01*
G01X690969Y94309D02*
G03X691957Y93321I988J0D01*
G01Y92096D02*
G02X689744Y94309I0J2213D01*
G01X690969Y101679D02*
Y94309D01*
G01X689744D02*
Y101171D01*
G01X685640Y107008D02*
X690969Y101679D01*
G01X689744Y101171D02*
X684415Y106500D01*
G01X685640Y112460D02*
Y107008D01*
G01X684415Y106500D02*
Y111648D01*
G01X683871Y92132D02*
X685141D01*
G01X683871Y93357D02*
X685142D01*
G01X681742Y94261D02*
G03X683871Y92132I2129J0D01*
G01X682967Y94261D02*
G03X683871Y93357I904J0D01*
G01X681742Y101919D02*
Y94261D01*
G01X682967Y102427D02*
Y94261D01*
G01X681102Y102559D02*
X681742Y101919D01*
G01X682327Y103067D02*
X682967Y102427D01*
G01X681102Y111811D02*
Y102559D01*
G01X682327Y110935D02*
Y103067D01*
G01X683871Y93357D02*
X685142D01*
G01X683871Y92132D02*
X685141D01*
G01X682967Y94261D02*
G03X683871Y93357I904J0D01*
G01X681742Y94261D02*
G03X683871Y92132I2129J0D01*
G01X682967Y102427D02*
Y94261D01*
G01X681742Y101919D02*
Y94261D01*
G01X682327Y103067D02*
X682967Y102427D01*
G01X681102Y102559D02*
X681742Y101919D01*
G01X682327Y110935D02*
Y103067D01*
G01X681102Y111811D02*
Y102559D01*
G01X675817Y92134D02*
X677087D01*
G01X675817Y93359D02*
X677088D01*
G01X673812Y94139D02*
G03X675817Y92134I2005J0D01*
G01X675037Y94139D02*
G03X675817Y93359I780J0D01*
G01X673812Y103566D02*
Y94139D01*
G01X675037Y103058D02*
Y94139D01*
G01X674982Y104736D02*
X673812Y103566D01*
G01X676207Y104228D02*
X675037Y103058D01*
G01X674982Y111632D02*
Y104736D01*
G01X676207Y112140D02*
Y104228D01*
G01X675817Y93359D02*
X677088D01*
G01X675817Y92134D02*
X677087D01*
G01X675037Y94139D02*
G03X675817Y93359I780J0D01*
G01X673812Y94139D02*
G03X675817Y92134I2005J0D01*
G01X675037Y103058D02*
Y94139D01*
G01X673812Y103566D02*
Y94139D01*
G01X676207Y104228D02*
X675037Y103058D01*
G01X674982Y104736D02*
X673812Y103566D01*
G01X676207Y112140D02*
Y104228D01*
G01X674982Y111632D02*
Y104736D01*
G01X667738Y92143D02*
X669008D01*
G01X667738Y93368D02*
X669009D01*
G01X665772Y94109D02*
G03X667738Y92143I1966J0D01*
G01X666997Y94109D02*
G03X667738Y93368I741J0D01*
G01X665772Y101137D02*
Y94109D01*
G01X666997Y100629D02*
Y94109D01*
G01X671816Y107181D02*
X665772Y101137D01*
G01X673041Y106673D02*
X666997Y100629D01*
G01X671816Y111648D02*
Y107181D01*
G01X673041Y113572D02*
Y106673D01*
G01X667738Y93368D02*
X669009D01*
G01X667738Y92143D02*
X669008D01*
G01X666997Y94109D02*
G03X667738Y93368I741J0D01*
G01X665772Y94109D02*
G03X667738Y92143I1966J0D01*
G01X666997Y100629D02*
Y94109D01*
G01X665772Y101137D02*
Y94109D01*
G01X673041Y106673D02*
X666997Y100629D01*
G01X671816Y107181D02*
X665772Y101137D01*
G01X673041Y113572D02*
Y106673D01*
G01X671816Y111648D02*
Y107181D01*
G01X659639Y92177D02*
X660909D01*
G01X659639Y93402D02*
X660910D01*
G01X657565Y94251D02*
G03X659639Y92177I2074J0D01*
G01X658790Y94251D02*
G03X659639Y93402I849J0D01*
G01X657565Y99411D02*
Y94251D01*
G01X658790Y98903D02*
Y94251D01*
G01X665517Y107363D02*
X657565Y99411D01*
G01X666742Y106855D02*
X658790Y98903D01*
G01X665517Y111648D02*
Y107363D01*
G01X666742Y113572D02*
Y106855D01*
G01X659639Y93402D02*
X660910D01*
G01X659639Y92177D02*
X660909D01*
G01X658790Y94251D02*
G03X659639Y93402I849J0D01*
G01X657565Y94251D02*
G03X659639Y92177I2074J0D01*
G01X658790Y98903D02*
Y94251D01*
G01X657565Y99411D02*
Y94251D01*
G01X666742Y106855D02*
X658790Y98903D01*
G01X665517Y107363D02*
X657565Y99411D01*
G01X666742Y113572D02*
Y106855D01*
G01X665517Y111648D02*
Y107363D01*
G01X652031Y92346D02*
X652899D01*
G01X652031Y93571D02*
X652900D01*
G01X650231Y94146D02*
G03X652031Y92346I1800J0D01*
G01X651456Y94146D02*
G03X652031Y93571I575J0D01*
G01X650231Y99559D02*
Y94146D01*
G01X651456Y99051D02*
Y94146D01*
G01X662204Y111532D02*
X650231Y99559D01*
G01X663700Y111295D02*
X651456Y99051D01*
G01X652031Y93571D02*
X652900D01*
G01X652031Y92346D02*
X652899D01*
G01X651456Y94146D02*
G03X652031Y93571I575J0D01*
G01X650231Y94146D02*
G03X652031Y92346I1800J0D01*
G01X651456Y99051D02*
Y94146D01*
G01X650231Y99559D02*
Y94146D01*
G01X663700Y111295D02*
X651456Y99051D01*
G01X662204Y111532D02*
X650231Y99559D01*
G01X653718Y110171D02*
Y110849D01*
G01X654943Y110172D02*
Y110849D01*
G01X653270Y109089D02*
G03X653718Y110171I-1082J1082D01*
G01X654136Y108222D02*
G03X654943Y110172I-1948J1948D01*
G01X640830Y96649D02*
X653270Y109089D01*
G01X642055Y96141D02*
X654136Y108222D01*
G01X640830Y95624D02*
Y96649D01*
G01X642055Y95623D02*
Y96141D01*
G01X653718Y110171D02*
Y110849D01*
G01X654943Y110172D02*
Y110849D01*
G01X653270Y109089D02*
G03X653718Y110171I-1082J1082D01*
G01X654136Y108222D02*
G03X654943Y110172I-1948J1948D01*
G01X640830Y96649D02*
X653270Y109089D01*
G01X642055Y96141D02*
X654136Y108222D01*
G01X640830Y95624D02*
Y96649D01*
G01X642055Y95623D02*
Y96141D01*
G01X654943Y110172D02*
Y110849D01*
G01X653718Y110171D02*
Y110849D01*
G01X654136Y108222D02*
G03X654943Y110172I-1948J1948D01*
G01X653270Y109089D02*
G03X653718Y110171I-1082J1082D01*
G01X642055Y96141D02*
X654136Y108222D01*
G01X640830Y96649D02*
X653270Y109089D01*
G01X642055Y95623D02*
Y96141D01*
G01X640830Y95624D02*
Y96649D01*
G01X654943Y110172D02*
Y110849D01*
G01X653718Y110171D02*
Y110849D01*
G01X654136Y108222D02*
G03X654943Y110172I-1948J1948D01*
G01X653270Y109089D02*
G03X653718Y110171I-1082J1082D01*
G01X642055Y96141D02*
X654136Y108222D01*
G01X640830Y96649D02*
X653270Y109089D01*
G01X642055Y95623D02*
Y96141D01*
G01X640830Y95624D02*
Y96649D01*
G01Y80652D02*
Y83578D01*
G01X642055Y81160D02*
Y83578D01*
G01X644999Y76483D02*
X640830Y80652D01*
G01X645507Y77708D02*
X642055Y81160D01*
G01X663632Y76483D02*
X644999D01*
G01X664140Y77708D02*
X645507D01*
G01X672275Y67840D02*
X663632Y76483D01*
G01X673500Y68348D02*
X664140Y77708D01*
G01X672275Y61185D02*
Y67840D01*
G01X673500Y61693D02*
Y68348D01*
G01X676059Y59134D02*
X673500Y61693D01*
G01X679347Y55846D02*
X678127Y57066D01*
G01X682635Y52558D02*
X681415Y53778D01*
G01X642055Y81160D02*
Y83578D01*
G01X640830Y80652D02*
Y83578D01*
G01X645507Y77708D02*
X642055Y81160D01*
G01X644999Y76483D02*
X640830Y80652D01*
G01X664140Y77708D02*
X645507D01*
G01X663632Y76483D02*
X644999D01*
G01X673500Y68348D02*
X664140Y77708D01*
G01X672275Y67840D02*
X663632Y76483D01*
G01X673500Y61693D02*
Y68348D01*
G01X672275Y61185D02*
Y67840D01*
G01X676059Y59134D02*
X673500Y61693D01*
G01X679347Y55846D02*
X678127Y57066D01*
G01X682635Y52558D02*
X681415Y53778D01*
G01X707968Y31277D02*
X702183D01*
G01X707967Y32502D02*
X702691D01*
G01X707967D02*
X702691D01*
G01X707968Y31277D02*
X702183D01*
G01X707970Y94037D02*
X709240D01*
G01X707970Y95262D02*
X709241D01*
G01X705970Y96037D02*
G03X707970Y94037I2000J0D01*
G01X707195Y96037D02*
G03X707970Y95262I775J0D01*
G01X705970Y99707D02*
Y96037D01*
G01X707195Y100215D02*
Y96037D01*
G01X703906Y101771D02*
X705970Y99707D01*
G01X704414Y102996D02*
X707195Y100215D01*
G01X701363Y101771D02*
X703906D01*
G01X701871Y102996D02*
X704414D01*
G01X707970Y95262D02*
X709241D01*
G01X707970Y94037D02*
X709240D01*
G01X707195Y96037D02*
G03X707970Y95262I775J0D01*
G01X705970Y96037D02*
G03X707970Y94037I2000J0D01*
G01X707195Y100215D02*
Y96037D01*
G01X705970Y99707D02*
Y96037D01*
G01X704414Y102996D02*
X707195Y100215D01*
G01X703906Y101771D02*
X705970Y99707D01*
G01X701871Y102996D02*
X704414D01*
G01X701363Y101771D02*
X703906D01*
G01X697983Y94148D02*
Y99507D01*
G01X699208Y100015D02*
Y94148D01*
G01X699983Y92148D02*
G02X697983Y94148I0J2000D01*
G01X699208D02*
G03X699983Y93373I775J0D01*
G01X701253Y92148D02*
X699983D01*
G01Y93373D02*
X701254D01*
G01X699983D02*
X701254D01*
G01X701253Y92148D02*
X699983D01*
G01X699208Y94148D02*
G03X699983Y93373I775J0D01*
G01Y92148D02*
G02X697983Y94148I0J2000D01*
G01X699208Y100015D02*
Y94148D01*
G01X697983D02*
Y99507D01*
M02*
